FILE_TYPE = MACRO_DRAWING;
SET COLOR_WIRE YELLOW;
SET COLOR_PROP ORANGE;
SET COLOR_DOT WHITE;
SET COLOR_ARC YELLOW;
SET COLOR_BODY GREEN;
SET COLOR_NOTE PURPLE;
SET PROP_DISPLAY VALUE;
SET PAGE_NUMBER P68;
FORCEADD Q_CAP..1
(-9000 2075);
FORCEPROP 1 LAST LOCATION C2167
J 0
(-8950 2175);
DISPLAY 0.489362 (-8950 2175);
PAINT SKYBLUE (-8950 2175);
FORCEPROP 2 LAST $SEC 1
J 0
(-8950 2275);
DISPLAY 0.680851 (-8950 2275);
PAINT MONO (-8950 2275);
DISPLAY INVISIBLE (-8950 2275);
FORCEPROP 2 LAST CDS_SEC 1
J 0
(-8950 2275);
DISPLAY 1.021277 (-8950 2275);
DISPLAY INVISIBLE (-8950 2275);
FORCEPROP 1 LASTPIN (-9000 2175) $PN 1
J 0
(-8990 2155);
DISPLAY 0.489362 (-8990 2155);
FORCEPROP 1 LASTPIN (-9000 1975) $PN 2
J 0
(-8990 1955);
DISPLAY 0.489362 (-8990 1955);
FORCEPROP 1 LAST VALUE 22UF
J 0
(-8950 2125);
DISPLAY 0.489362 (-8950 2125);
PAINT SKYBLUE (-8950 2125);
FORCEPROP 1 LAST VOLTAGE 4V
J 0
(-8950 2075);
DISPLAY 0.489362 (-8950 2075);
PAINT SKYBLUE (-8950 2075);
FORCEPROP 1 LAST PACK_TYPE C0402
J 0
(-8950 1875);
DISPLAY 0.489362 (-8950 1875);
PAINT SKYBLUE (-8950 1875);
FORCEPROP 1 LAST TOLERANCE 20%
J 0
(-8950 2025);
DISPLAY 0.489362 (-8950 2025);
PAINT SKYBLUE (-8950 2025);
FORCEPROP 1 LAST MATERIAL X6S
J 0
(-8950 1975);
DISPLAY 0.489362 (-8950 1975);
PAINT SKYBLUE (-8950 1975);
FORCEPROP 2 LAST CDS_LIB pure_quanta
J 0
(-9000 2075);
PAINT MONO (-9000 2075);
DISPLAY INVISIBLE (-9000 2075);
FORCEPROP 1 LAST PATH I1
J 0
(-8950 2225);
DISPLAY 0.978723 (-8950 2225);
PAINT WHITE (-8950 2225);
DISPLAY INVISIBLE (-8950 2225);
FORCEPROP 1 LAST PART_NUMBER CH622KMEB02
J 0
(-8950 1925);
DISPLAY 0.489362 (-8950 1925);
PAINT SKYBLUE (-8950 1925);
DISPLAY INVISIBLE (-8950 1925);
FORCEADD Q_CAP..1
(-9000 4475);
FORCEPROP 1 LAST LOCATION C246
J 0
(-8950 4575);
DISPLAY 0.489362 (-8950 4575);
PAINT SKYBLUE (-8950 4575);
FORCEPROP 2 LAST $SEC 1
J 0
(-8950 4675);
DISPLAY 0.680851 (-8950 4675);
PAINT MONO (-8950 4675);
DISPLAY INVISIBLE (-8950 4675);
FORCEPROP 2 LAST CDS_SEC 1
J 0
(-8950 4675);
DISPLAY 1.021277 (-8950 4675);
DISPLAY INVISIBLE (-8950 4675);
FORCEPROP 1 LASTPIN (-9000 4575) $PN 1
J 0
(-8990 4555);
DISPLAY 0.489362 (-8990 4555);
FORCEPROP 1 LASTPIN (-9000 4375) $PN 2
J 0
(-8990 4355);
DISPLAY 0.489362 (-8990 4355);
FORCEPROP 1 LAST MATERIAL X6S
J 0
(-8950 4375);
DISPLAY 0.489362 (-8950 4375);
PAINT SKYBLUE (-8950 4375);
FORCEPROP 1 LAST TOLERANCE 20%
J 0
(-8950 4425);
DISPLAY 0.489362 (-8950 4425);
PAINT SKYBLUE (-8950 4425);
FORCEPROP 1 LAST VALUE 22UF
J 0
(-8950 4525);
DISPLAY 0.489362 (-8950 4525);
PAINT SKYBLUE (-8950 4525);
FORCEPROP 1 LAST VOLTAGE 4V
J 0
(-8950 4475);
DISPLAY 0.489362 (-8950 4475);
PAINT SKYBLUE (-8950 4475);
FORCEPROP 1 LAST PACK_TYPE C0402
J 0
(-8950 4275);
DISPLAY 0.489362 (-8950 4275);
PAINT SKYBLUE (-8950 4275);
FORCEPROP 2 LAST CDS_LIB pure_quanta
J 0
(-9000 4475);
PAINT MONO (-9000 4475);
DISPLAY INVISIBLE (-9000 4475);
FORCEPROP 1 LAST PATH I10
J 0
(-8950 4625);
DISPLAY 0.978723 (-8950 4625);
PAINT WHITE (-8950 4625);
DISPLAY INVISIBLE (-8950 4625);
FORCEPROP 1 LAST PART_NUMBER CH622KMEB02
J 0
(-8950 4325);
DISPLAY 0.489362 (-8950 4325);
PAINT SKYBLUE (-8950 4325);
DISPLAY INVISIBLE (-8950 4325);
FORCEADD Q_CAP..1
(-2175 5250);
FORCEPROP 1 LAST LOCATION C2231
J 0
(-2125 5350);
DISPLAY 0.489362 (-2125 5350);
PAINT SKYBLUE (-2125 5350);
FORCEPROP 2 LAST $SEC 1
J 0
(-2125 5450);
DISPLAY 0.680851 (-2125 5450);
PAINT MONO (-2125 5450);
DISPLAY INVISIBLE (-2125 5450);
FORCEPROP 2 LAST CDS_SEC 1
J 0
(-2125 5450);
DISPLAY 1.021277 (-2125 5450);
DISPLAY INVISIBLE (-2125 5450);
FORCEPROP 1 LASTPIN (-2175 5350) $PN 1
J 0
(-2165 5330);
DISPLAY 0.489362 (-2165 5330);
FORCEPROP 1 LASTPIN (-2175 5150) $PN 2
J 0
(-2165 5130);
DISPLAY 0.489362 (-2165 5130);
FORCEPROP 1 LAST MATERIAL X6S
J 0
(-2125 5150);
DISPLAY 0.489362 (-2125 5150);
PAINT SKYBLUE (-2125 5150);
FORCEPROP 1 LAST TOLERANCE 20%
J 0
(-2125 5200);
DISPLAY 0.489362 (-2125 5200);
PAINT SKYBLUE (-2125 5200);
FORCEPROP 1 LAST VALUE 22UF
J 0
(-2125 5300);
DISPLAY 0.489362 (-2125 5300);
PAINT SKYBLUE (-2125 5300);
FORCEPROP 1 LAST VOLTAGE 4V
J 0
(-2125 5250);
DISPLAY 0.489362 (-2125 5250);
PAINT SKYBLUE (-2125 5250);
FORCEPROP 1 LAST PACK_TYPE C0402
J 0
(-2125 5050);
DISPLAY 0.489362 (-2125 5050);
PAINT SKYBLUE (-2125 5050);
FORCEPROP 2 LAST CDS_LIB pure_quanta
J 0
(-2175 5250);
PAINT MONO (-2175 5250);
DISPLAY INVISIBLE (-2175 5250);
FORCEPROP 1 LAST PATH I100
J 0
(-2125 5400);
DISPLAY 0.978723 (-2125 5400);
PAINT WHITE (-2125 5400);
DISPLAY INVISIBLE (-2125 5400);
FORCEPROP 1 LAST PART_NUMBER CH622KMEB02
J 0
(-2125 5100);
DISPLAY 0.489362 (-2125 5100);
PAINT SKYBLUE (-2125 5100);
DISPLAY INVISIBLE (-2125 5100);
FORCEADD Q_CAP..1
(-1725 4475);
FORCEPROP 1 LAST LOCATION C2238
J 0
(-1675 4575);
DISPLAY 0.489362 (-1675 4575);
PAINT SKYBLUE (-1675 4575);
FORCEPROP 2 LAST $SEC 1
J 0
(-1675 4675);
DISPLAY 0.680851 (-1675 4675);
PAINT MONO (-1675 4675);
DISPLAY INVISIBLE (-1675 4675);
FORCEPROP 2 LAST CDS_SEC 1
J 0
(-1675 4675);
DISPLAY 1.021277 (-1675 4675);
DISPLAY INVISIBLE (-1675 4675);
FORCEPROP 1 LASTPIN (-1725 4575) $PN 1
J 0
(-1715 4555);
DISPLAY 0.489362 (-1715 4555);
FORCEPROP 1 LASTPIN (-1725 4375) $PN 2
J 0
(-1715 4355);
DISPLAY 0.489362 (-1715 4355);
FORCEPROP 1 LAST MATERIAL X6S
J 0
(-1675 4375);
DISPLAY 0.489362 (-1675 4375);
PAINT SKYBLUE (-1675 4375);
FORCEPROP 1 LAST TOLERANCE 20%
J 0
(-1675 4425);
DISPLAY 0.489362 (-1675 4425);
PAINT SKYBLUE (-1675 4425);
FORCEPROP 1 LAST VALUE 22UF
J 0
(-1675 4525);
DISPLAY 0.489362 (-1675 4525);
PAINT SKYBLUE (-1675 4525);
FORCEPROP 1 LAST VOLTAGE 4V
J 0
(-1675 4475);
DISPLAY 0.489362 (-1675 4475);
PAINT SKYBLUE (-1675 4475);
FORCEPROP 1 LAST PACK_TYPE C0402
J 0
(-1675 4275);
DISPLAY 0.489362 (-1675 4275);
PAINT SKYBLUE (-1675 4275);
FORCEPROP 2 LAST CDS_LIB pure_quanta
J 0
(-1725 4475);
PAINT MONO (-1725 4475);
DISPLAY INVISIBLE (-1725 4475);
FORCEPROP 1 LAST PATH I101
J 0
(-1675 4625);
DISPLAY 0.978723 (-1675 4625);
PAINT WHITE (-1675 4625);
DISPLAY INVISIBLE (-1675 4625);
FORCEPROP 1 LAST PART_NUMBER CH622KMEB02
J 0
(-1675 4325);
DISPLAY 0.489362 (-1675 4325);
PAINT SKYBLUE (-1675 4325);
DISPLAY INVISIBLE (-1675 4325);
FORCEADD Q_CAP..1
(-1275 4475);
FORCEPROP 1 LAST LOCATION C2244
J 0
(-1225 4575);
DISPLAY 0.489362 (-1225 4575);
PAINT SKYBLUE (-1225 4575);
FORCEPROP 2 LAST $SEC 1
J 0
(-1225 4675);
DISPLAY 0.680851 (-1225 4675);
PAINT MONO (-1225 4675);
DISPLAY INVISIBLE (-1225 4675);
FORCEPROP 2 LAST CDS_SEC 1
J 0
(-1225 4675);
DISPLAY 1.021277 (-1225 4675);
DISPLAY INVISIBLE (-1225 4675);
FORCEPROP 1 LASTPIN (-1275 4575) $PN 1
J 0
(-1265 4555);
DISPLAY 0.489362 (-1265 4555);
FORCEPROP 1 LASTPIN (-1275 4375) $PN 2
J 0
(-1265 4355);
DISPLAY 0.489362 (-1265 4355);
FORCEPROP 1 LAST MATERIAL X6S
J 0
(-1225 4375);
DISPLAY 0.489362 (-1225 4375);
PAINT SKYBLUE (-1225 4375);
FORCEPROP 1 LAST TOLERANCE 20%
J 0
(-1225 4425);
DISPLAY 0.489362 (-1225 4425);
PAINT SKYBLUE (-1225 4425);
FORCEPROP 1 LAST VALUE 22UF
J 0
(-1225 4525);
DISPLAY 0.489362 (-1225 4525);
PAINT SKYBLUE (-1225 4525);
FORCEPROP 1 LAST VOLTAGE 4V
J 0
(-1225 4475);
DISPLAY 0.489362 (-1225 4475);
PAINT SKYBLUE (-1225 4475);
FORCEPROP 1 LAST PACK_TYPE C0402
J 0
(-1225 4275);
DISPLAY 0.489362 (-1225 4275);
PAINT SKYBLUE (-1225 4275);
FORCEPROP 2 LAST CDS_LIB pure_quanta
J 0
(-1275 4475);
PAINT MONO (-1275 4475);
DISPLAY INVISIBLE (-1275 4475);
FORCEPROP 1 LAST PATH I102
J 0
(-1225 4625);
DISPLAY 0.978723 (-1225 4625);
PAINT WHITE (-1225 4625);
DISPLAY INVISIBLE (-1225 4625);
FORCEPROP 1 LAST PART_NUMBER CH622KMEB02
J 0
(-1225 4325);
DISPLAY 0.489362 (-1225 4325);
PAINT SKYBLUE (-1225 4325);
DISPLAY INVISIBLE (-1225 4325);
FORCEADD Q_CAP..1
(-1725 5250);
FORCEPROP 1 LAST LOCATION C2237
J 0
(-1675 5350);
DISPLAY 0.489362 (-1675 5350);
PAINT SKYBLUE (-1675 5350);
FORCEPROP 2 LAST $SEC 1
J 0
(-1675 5450);
DISPLAY 0.680851 (-1675 5450);
PAINT MONO (-1675 5450);
DISPLAY INVISIBLE (-1675 5450);
FORCEPROP 2 LAST CDS_SEC 1
J 0
(-1675 5450);
DISPLAY 1.021277 (-1675 5450);
DISPLAY INVISIBLE (-1675 5450);
FORCEPROP 1 LASTPIN (-1725 5350) $PN 1
J 0
(-1715 5330);
DISPLAY 0.489362 (-1715 5330);
FORCEPROP 1 LASTPIN (-1725 5150) $PN 2
J 0
(-1715 5130);
DISPLAY 0.489362 (-1715 5130);
FORCEPROP 1 LAST MATERIAL X6S
J 0
(-1675 5150);
DISPLAY 0.489362 (-1675 5150);
PAINT SKYBLUE (-1675 5150);
FORCEPROP 1 LAST TOLERANCE 20%
J 0
(-1675 5200);
DISPLAY 0.489362 (-1675 5200);
PAINT SKYBLUE (-1675 5200);
FORCEPROP 1 LAST VALUE 22UF
J 0
(-1675 5300);
DISPLAY 0.489362 (-1675 5300);
PAINT SKYBLUE (-1675 5300);
FORCEPROP 1 LAST VOLTAGE 4V
J 0
(-1675 5250);
DISPLAY 0.489362 (-1675 5250);
PAINT SKYBLUE (-1675 5250);
FORCEPROP 1 LAST PACK_TYPE C0402
J 0
(-1675 5050);
DISPLAY 0.489362 (-1675 5050);
PAINT SKYBLUE (-1675 5050);
FORCEPROP 2 LAST CDS_LIB pure_quanta
J 0
(-1725 5250);
PAINT MONO (-1725 5250);
DISPLAY INVISIBLE (-1725 5250);
FORCEPROP 1 LAST PATH I103
J 0
(-1675 5400);
DISPLAY 0.978723 (-1675 5400);
PAINT WHITE (-1675 5400);
DISPLAY INVISIBLE (-1675 5400);
FORCEPROP 1 LAST PART_NUMBER CH622KMEB02
J 0
(-1675 5100);
DISPLAY 0.489362 (-1675 5100);
PAINT SKYBLUE (-1675 5100);
DISPLAY INVISIBLE (-1675 5100);
FORCEADD Q_CAP..1
(-1275 5250);
FORCEPROP 1 LAST LOCATION C2243
J 0
(-1225 5350);
DISPLAY 0.489362 (-1225 5350);
PAINT SKYBLUE (-1225 5350);
FORCEPROP 2 LAST $SEC 1
J 0
(-1225 5450);
DISPLAY 0.680851 (-1225 5450);
PAINT MONO (-1225 5450);
DISPLAY INVISIBLE (-1225 5450);
FORCEPROP 2 LAST CDS_SEC 1
J 0
(-1225 5450);
DISPLAY 1.021277 (-1225 5450);
DISPLAY INVISIBLE (-1225 5450);
FORCEPROP 1 LASTPIN (-1275 5350) $PN 1
J 0
(-1265 5330);
DISPLAY 0.489362 (-1265 5330);
FORCEPROP 1 LASTPIN (-1275 5150) $PN 2
J 0
(-1265 5130);
DISPLAY 0.489362 (-1265 5130);
FORCEPROP 1 LAST MATERIAL X6S
J 0
(-1225 5150);
DISPLAY 0.489362 (-1225 5150);
PAINT SKYBLUE (-1225 5150);
FORCEPROP 1 LAST TOLERANCE 20%
J 0
(-1225 5200);
DISPLAY 0.489362 (-1225 5200);
PAINT SKYBLUE (-1225 5200);
FORCEPROP 1 LAST VALUE 22UF
J 0
(-1225 5300);
DISPLAY 0.489362 (-1225 5300);
PAINT SKYBLUE (-1225 5300);
FORCEPROP 1 LAST VOLTAGE 4V
J 0
(-1225 5250);
DISPLAY 0.489362 (-1225 5250);
PAINT SKYBLUE (-1225 5250);
FORCEPROP 1 LAST PACK_TYPE C0402
J 0
(-1225 5050);
DISPLAY 0.489362 (-1225 5050);
PAINT SKYBLUE (-1225 5050);
FORCEPROP 2 LAST CDS_LIB pure_quanta
J 0
(-1275 5250);
PAINT MONO (-1275 5250);
DISPLAY INVISIBLE (-1275 5250);
FORCEPROP 1 LAST PATH I104
J 0
(-1225 5400);
DISPLAY 0.978723 (-1225 5400);
PAINT WHITE (-1225 5400);
DISPLAY INVISIBLE (-1225 5400);
FORCEPROP 1 LAST PART_NUMBER CH622KMEB02
J 0
(-1225 5100);
DISPLAY 0.489362 (-1225 5100);
PAINT SKYBLUE (-1225 5100);
DISPLAY INVISIBLE (-1225 5100);
FORCEADD Q_CAP..1
(-825 4475);
FORCEPROP 1 LAST LOCATION C2249
J 0
(-775 4575);
DISPLAY 0.489362 (-775 4575);
PAINT SKYBLUE (-775 4575);
FORCEPROP 2 LAST $SEC 1
J 0
(-775 4675);
DISPLAY 0.680851 (-775 4675);
PAINT MONO (-775 4675);
DISPLAY INVISIBLE (-775 4675);
FORCEPROP 2 LAST CDS_SEC 1
J 0
(-775 4675);
DISPLAY 1.021277 (-775 4675);
DISPLAY INVISIBLE (-775 4675);
FORCEPROP 1 LASTPIN (-825 4575) $PN 1
J 0
(-815 4555);
DISPLAY 0.489362 (-815 4555);
FORCEPROP 1 LASTPIN (-825 4375) $PN 2
J 0
(-815 4355);
DISPLAY 0.489362 (-815 4355);
FORCEPROP 1 LAST MATERIAL X6S
J 0
(-775 4375);
DISPLAY 0.489362 (-775 4375);
PAINT SKYBLUE (-775 4375);
FORCEPROP 1 LAST TOLERANCE 20%
J 0
(-775 4425);
DISPLAY 0.489362 (-775 4425);
PAINT SKYBLUE (-775 4425);
FORCEPROP 1 LAST VALUE 22UF
J 0
(-775 4525);
DISPLAY 0.489362 (-775 4525);
PAINT SKYBLUE (-775 4525);
FORCEPROP 1 LAST VOLTAGE 4V
J 0
(-775 4475);
DISPLAY 0.489362 (-775 4475);
PAINT SKYBLUE (-775 4475);
FORCEPROP 1 LAST PACK_TYPE C0402
J 0
(-775 4275);
DISPLAY 0.489362 (-775 4275);
PAINT SKYBLUE (-775 4275);
FORCEPROP 2 LAST CDS_LIB pure_quanta
J 0
(-825 4475);
PAINT MONO (-825 4475);
DISPLAY INVISIBLE (-825 4475);
FORCEPROP 1 LAST PATH I105
J 0
(-775 4625);
DISPLAY 0.978723 (-775 4625);
PAINT WHITE (-775 4625);
DISPLAY INVISIBLE (-775 4625);
FORCEPROP 1 LAST PART_NUMBER CH622KMEB02
J 0
(-775 4325);
DISPLAY 0.489362 (-775 4325);
PAINT SKYBLUE (-775 4325);
DISPLAY INVISIBLE (-775 4325);
FORCEADD Q_CAP..1
(-425 4475);
FORCEPROP 1 LAST LOCATION C2254
J 0
(-375 4575);
DISPLAY 0.489362 (-375 4575);
PAINT SKYBLUE (-375 4575);
FORCEPROP 2 LAST $SEC 1
J 0
(-375 4675);
DISPLAY 0.680851 (-375 4675);
PAINT MONO (-375 4675);
DISPLAY INVISIBLE (-375 4675);
FORCEPROP 2 LAST CDS_SEC 1
J 0
(-375 4675);
DISPLAY 1.021277 (-375 4675);
DISPLAY INVISIBLE (-375 4675);
FORCEPROP 1 LASTPIN (-425 4575) $PN 1
J 0
(-415 4555);
DISPLAY 0.489362 (-415 4555);
FORCEPROP 1 LASTPIN (-425 4375) $PN 2
J 0
(-415 4355);
DISPLAY 0.489362 (-415 4355);
FORCEPROP 1 LAST MATERIAL X6S
J 0
(-375 4375);
DISPLAY 0.489362 (-375 4375);
PAINT SKYBLUE (-375 4375);
FORCEPROP 1 LAST TOLERANCE 20%
J 0
(-375 4425);
DISPLAY 0.489362 (-375 4425);
PAINT SKYBLUE (-375 4425);
FORCEPROP 1 LAST VALUE 22UF
J 0
(-375 4525);
DISPLAY 0.489362 (-375 4525);
PAINT SKYBLUE (-375 4525);
FORCEPROP 1 LAST VOLTAGE 4V
J 0
(-375 4475);
DISPLAY 0.489362 (-375 4475);
PAINT SKYBLUE (-375 4475);
FORCEPROP 1 LAST PACK_TYPE C0402
J 0
(-375 4275);
DISPLAY 0.489362 (-375 4275);
PAINT SKYBLUE (-375 4275);
FORCEPROP 2 LAST CDS_LIB pure_quanta
J 0
(-425 4475);
PAINT MONO (-425 4475);
DISPLAY INVISIBLE (-425 4475);
FORCEPROP 1 LAST PATH I106
J 0
(-375 4625);
DISPLAY 0.978723 (-375 4625);
PAINT WHITE (-375 4625);
DISPLAY INVISIBLE (-375 4625);
FORCEPROP 1 LAST PART_NUMBER CH622KMEB02
J 0
(-375 4325);
DISPLAY 0.489362 (-375 4325);
PAINT SKYBLUE (-375 4325);
DISPLAY INVISIBLE (-375 4325);
FORCEADD UNIVERSAL_GND..1
(-425 4875);
FORCEPROP 3 LASTPIN (-425 4925) SIG_NAME GND\g
J 0
(-415 4935);
DISPLAY 0.659574 (-415 4935);
PAINT MONO (-415 4935);
DISPLAY INVISIBLE (-415 4935);
FORCEPROP 2 LAST CDS_LIB pure_quanta_power
J 0
(-425 4875);
PAINT MONO (-425 4875);
DISPLAY INVISIBLE (-425 4875);
FORCEPROP 1 LAST HDL_POWER GND
J 1
(-400 4800);
DISPLAY 0.872340 (-400 4800);
PAINT GREEN (-400 4800);
DISPLAY INVISIBLE (-400 4800);
FORCEPROP 1 LAST PATH I107
J 0
(-350 4875);
DISPLAY 0.872340 (-350 4875);
PAINT AQUA (-350 4875);
DISPLAY INVISIBLE (-350 4875);
FORCEADD Q_CAP..1
(-825 5250);
FORCEPROP 1 LAST LOCATION C2248
J 0
(-775 5350);
DISPLAY 0.489362 (-775 5350);
PAINT SKYBLUE (-775 5350);
FORCEPROP 2 LAST $SEC 1
J 0
(-775 5450);
DISPLAY 0.680851 (-775 5450);
PAINT MONO (-775 5450);
DISPLAY INVISIBLE (-775 5450);
FORCEPROP 2 LAST CDS_SEC 1
J 0
(-775 5450);
DISPLAY 1.021277 (-775 5450);
DISPLAY INVISIBLE (-775 5450);
FORCEPROP 1 LASTPIN (-825 5350) $PN 1
J 0
(-815 5330);
DISPLAY 0.489362 (-815 5330);
FORCEPROP 1 LASTPIN (-825 5150) $PN 2
J 0
(-815 5130);
DISPLAY 0.489362 (-815 5130);
FORCEPROP 1 LAST MATERIAL X6S
J 0
(-775 5150);
DISPLAY 0.489362 (-775 5150);
PAINT SKYBLUE (-775 5150);
FORCEPROP 1 LAST TOLERANCE 20%
J 0
(-775 5200);
DISPLAY 0.489362 (-775 5200);
PAINT SKYBLUE (-775 5200);
FORCEPROP 1 LAST VALUE 22UF
J 0
(-775 5300);
DISPLAY 0.489362 (-775 5300);
PAINT SKYBLUE (-775 5300);
FORCEPROP 1 LAST VOLTAGE 4V
J 0
(-775 5250);
DISPLAY 0.489362 (-775 5250);
PAINT SKYBLUE (-775 5250);
FORCEPROP 1 LAST PACK_TYPE C0402
J 0
(-775 5050);
DISPLAY 0.489362 (-775 5050);
PAINT SKYBLUE (-775 5050);
FORCEPROP 2 LAST CDS_LIB pure_quanta
J 0
(-825 5250);
PAINT MONO (-825 5250);
DISPLAY INVISIBLE (-825 5250);
FORCEPROP 1 LAST PATH I108
J 0
(-775 5400);
DISPLAY 0.978723 (-775 5400);
PAINT WHITE (-775 5400);
DISPLAY INVISIBLE (-775 5400);
FORCEPROP 1 LAST PART_NUMBER CH622KMEB02
J 0
(-775 5100);
DISPLAY 0.489362 (-775 5100);
PAINT SKYBLUE (-775 5100);
DISPLAY INVISIBLE (-775 5100);
FORCEADD Q_CAP..1
(-425 5250);
FORCEPROP 1 LAST LOCATION C2253
J 0
(-375 5350);
DISPLAY 0.489362 (-375 5350);
PAINT SKYBLUE (-375 5350);
FORCEPROP 2 LAST $SEC 1
J 0
(-375 5450);
DISPLAY 0.680851 (-375 5450);
PAINT MONO (-375 5450);
DISPLAY INVISIBLE (-375 5450);
FORCEPROP 2 LAST CDS_SEC 1
J 0
(-375 5450);
DISPLAY 1.021277 (-375 5450);
DISPLAY INVISIBLE (-375 5450);
FORCEPROP 1 LASTPIN (-425 5350) $PN 1
J 0
(-415 5330);
DISPLAY 0.489362 (-415 5330);
FORCEPROP 1 LASTPIN (-425 5150) $PN 2
J 0
(-415 5130);
DISPLAY 0.489362 (-415 5130);
FORCEPROP 1 LAST MATERIAL X6S
J 0
(-375 5150);
DISPLAY 0.489362 (-375 5150);
PAINT SKYBLUE (-375 5150);
FORCEPROP 1 LAST TOLERANCE 20%
J 0
(-375 5200);
DISPLAY 0.489362 (-375 5200);
PAINT SKYBLUE (-375 5200);
FORCEPROP 1 LAST VALUE 22UF
J 0
(-375 5300);
DISPLAY 0.489362 (-375 5300);
PAINT SKYBLUE (-375 5300);
FORCEPROP 1 LAST VOLTAGE 4V
J 0
(-375 5250);
DISPLAY 0.489362 (-375 5250);
PAINT SKYBLUE (-375 5250);
FORCEPROP 1 LAST PACK_TYPE C0402
J 0
(-375 5050);
DISPLAY 0.489362 (-375 5050);
PAINT SKYBLUE (-375 5050);
FORCEPROP 2 LAST CDS_LIB pure_quanta
J 0
(-425 5250);
PAINT MONO (-425 5250);
DISPLAY INVISIBLE (-425 5250);
FORCEPROP 1 LAST PATH I109
J 0
(-375 5400);
DISPLAY 0.978723 (-375 5400);
PAINT WHITE (-375 5400);
DISPLAY INVISIBLE (-375 5400);
FORCEPROP 1 LAST PART_NUMBER CH622KMEB02
J 0
(-375 5100);
DISPLAY 0.489362 (-375 5100);
PAINT SKYBLUE (-375 5100);
DISPLAY INVISIBLE (-375 5100);
FORCEADD UNIVERSAL_POWER..1
(-9000 4750);
FORCEPROP 3 LASTPIN (-9000 4700) SIG_NAME PVDDCR_CPU0_P0\g
J 0
(-8990 4710);
DISPLAY 0.659574 (-8990 4710);
PAINT MONO (-8990 4710);
DISPLAY INVISIBLE (-8990 4710);
FORCEPROP 1 LAST HDL_POWER PVDDCR_CPU0_P0
J 1
(-9000 4800);
DISPLAY 0.489362 (-9000 4800);
PAINT GREEN (-9000 4800);
FORCEPROP 2 LAST CDS_LIB pure_quanta_power
J 0
(-9000 4750);
DISPLAY INVISIBLE (-9000 4750);
FORCEPROP 1 LAST PATH I11
J 0
(-8950 4775);
DISPLAY 0.872340 (-8950 4775);
PAINT AQUA (-8950 4775);
DISPLAY INVISIBLE (-8950 4775);
FORCEADD Q_CAP..1
(-6300 5250);
FORCEPROP 1 LAST LOCATION C272
J 0
(-6250 5350);
DISPLAY 0.489362 (-6250 5350);
PAINT SKYBLUE (-6250 5350);
FORCEPROP 2 LAST $SEC 1
J 0
(-6250 5450);
DISPLAY 0.680851 (-6250 5450);
PAINT MONO (-6250 5450);
DISPLAY INVISIBLE (-6250 5450);
FORCEPROP 2 LAST CDS_SEC 1
J 0
(-6250 5450);
DISPLAY 1.021277 (-6250 5450);
DISPLAY INVISIBLE (-6250 5450);
FORCEPROP 1 LASTPIN (-6300 5350) $PN 1
J 0
(-6290 5330);
DISPLAY 0.489362 (-6290 5330);
FORCEPROP 1 LASTPIN (-6300 5150) $PN 2
J 0
(-6290 5130);
DISPLAY 0.489362 (-6290 5130);
FORCEPROP 1 LAST MATERIAL X6S
J 0
(-6250 5150);
DISPLAY 0.489362 (-6250 5150);
PAINT SKYBLUE (-6250 5150);
FORCEPROP 1 LAST TOLERANCE 20%
J 0
(-6250 5200);
DISPLAY 0.489362 (-6250 5200);
PAINT SKYBLUE (-6250 5200);
FORCEPROP 1 LAST VALUE 22UF
J 0
(-6250 5300);
DISPLAY 0.489362 (-6250 5300);
PAINT SKYBLUE (-6250 5300);
FORCEPROP 1 LAST VOLTAGE 4V
J 0
(-6250 5250);
DISPLAY 0.489362 (-6250 5250);
PAINT SKYBLUE (-6250 5250);
FORCEPROP 1 LAST PACK_TYPE C0402
J 0
(-6250 5050);
DISPLAY 0.489362 (-6250 5050);
PAINT SKYBLUE (-6250 5050);
FORCEPROP 2 LAST CDS_LIB pure_quanta
J 0
(-6300 5250);
PAINT MONO (-6300 5250);
DISPLAY INVISIBLE (-6300 5250);
FORCEPROP 1 LAST PATH I110
J 0
(-6250 5400);
DISPLAY 0.978723 (-6250 5400);
PAINT WHITE (-6250 5400);
DISPLAY INVISIBLE (-6250 5400);
FORCEPROP 1 LAST PART_NUMBER CH622KMEB02
J 0
(-6250 5100);
DISPLAY 0.489362 (-6250 5100);
PAINT SKYBLUE (-6250 5100);
DISPLAY INVISIBLE (-6250 5100);
FORCEADD Q_CAP..1
(-8550 4475);
FORCEPROP 1 LAST LOCATION C252
J 0
(-8500 4575);
DISPLAY 0.489362 (-8500 4575);
PAINT SKYBLUE (-8500 4575);
FORCEPROP 2 LAST $SEC 1
J 0
(-8500 4675);
DISPLAY 0.680851 (-8500 4675);
PAINT MONO (-8500 4675);
DISPLAY INVISIBLE (-8500 4675);
FORCEPROP 2 LAST CDS_SEC 1
J 0
(-8500 4675);
DISPLAY 1.021277 (-8500 4675);
DISPLAY INVISIBLE (-8500 4675);
FORCEPROP 1 LASTPIN (-8550 4575) $PN 1
J 0
(-8540 4555);
DISPLAY 0.489362 (-8540 4555);
FORCEPROP 1 LASTPIN (-8550 4375) $PN 2
J 0
(-8540 4355);
DISPLAY 0.489362 (-8540 4355);
FORCEPROP 1 LAST MATERIAL X6S
J 0
(-8500 4375);
DISPLAY 0.489362 (-8500 4375);
PAINT SKYBLUE (-8500 4375);
FORCEPROP 1 LAST TOLERANCE 20%
J 0
(-8500 4425);
DISPLAY 0.489362 (-8500 4425);
PAINT SKYBLUE (-8500 4425);
FORCEPROP 1 LAST VALUE 22UF
J 0
(-8500 4525);
DISPLAY 0.489362 (-8500 4525);
PAINT SKYBLUE (-8500 4525);
FORCEPROP 1 LAST VOLTAGE 4V
J 0
(-8500 4475);
DISPLAY 0.489362 (-8500 4475);
PAINT SKYBLUE (-8500 4475);
FORCEPROP 1 LAST PACK_TYPE C0402
J 0
(-8500 4275);
DISPLAY 0.489362 (-8500 4275);
PAINT SKYBLUE (-8500 4275);
FORCEPROP 2 LAST CDS_LIB pure_quanta
J 0
(-8550 4475);
PAINT MONO (-8550 4475);
DISPLAY INVISIBLE (-8550 4475);
FORCEPROP 1 LAST PATH I12
J 0
(-8500 4625);
DISPLAY 0.978723 (-8500 4625);
PAINT WHITE (-8500 4625);
DISPLAY INVISIBLE (-8500 4625);
FORCEPROP 1 LAST PART_NUMBER CH622KMEB02
J 0
(-8500 4325);
DISPLAY 0.489362 (-8500 4325);
PAINT SKYBLUE (-8500 4325);
DISPLAY INVISIBLE (-8500 4325);
FORCEADD UNIVERSAL_POWER..1
(-9000 5525);
FORCEPROP 3 LASTPIN (-9000 5475) SIG_NAME PVDDCR_CPU0_P0\g
J 0
(-8990 5485);
DISPLAY 0.659574 (-8990 5485);
PAINT MONO (-8990 5485);
DISPLAY INVISIBLE (-8990 5485);
FORCEPROP 1 LAST HDL_POWER PVDDCR_CPU0_P0
J 1
(-9000 5575);
DISPLAY 0.489362 (-9000 5575);
PAINT GREEN (-9000 5575);
FORCEPROP 2 LAST CDS_LIB pure_quanta_power
J 0
(-9000 5525);
DISPLAY INVISIBLE (-9000 5525);
FORCEPROP 1 LAST PATH I13
J 0
(-8950 5550);
DISPLAY 0.872340 (-8950 5550);
PAINT AQUA (-8950 5550);
DISPLAY INVISIBLE (-8950 5550);
FORCEADD Q_CAP..1
(-9000 5250);
FORCEPROP 1 LAST LOCATION C245
J 0
(-8950 5350);
DISPLAY 0.489362 (-8950 5350);
PAINT SKYBLUE (-8950 5350);
FORCEPROP 2 LAST $SEC 1
J 0
(-8950 5450);
DISPLAY 0.680851 (-8950 5450);
PAINT MONO (-8950 5450);
DISPLAY INVISIBLE (-8950 5450);
FORCEPROP 2 LAST CDS_SEC 1
J 0
(-8950 5450);
DISPLAY 1.021277 (-8950 5450);
DISPLAY INVISIBLE (-8950 5450);
FORCEPROP 1 LASTPIN (-9000 5350) $PN 1
J 0
(-8990 5330);
DISPLAY 0.489362 (-8990 5330);
FORCEPROP 1 LASTPIN (-9000 5150) $PN 2
J 0
(-8990 5130);
DISPLAY 0.489362 (-8990 5130);
FORCEPROP 1 LAST MATERIAL X6S
J 0
(-8950 5150);
DISPLAY 0.489362 (-8950 5150);
PAINT SKYBLUE (-8950 5150);
FORCEPROP 1 LAST TOLERANCE 20%
J 0
(-8950 5200);
DISPLAY 0.489362 (-8950 5200);
PAINT SKYBLUE (-8950 5200);
FORCEPROP 1 LAST VALUE 22UF
J 0
(-8950 5300);
DISPLAY 0.489362 (-8950 5300);
PAINT SKYBLUE (-8950 5300);
FORCEPROP 1 LAST VOLTAGE 4V
J 0
(-8950 5250);
DISPLAY 0.489362 (-8950 5250);
PAINT SKYBLUE (-8950 5250);
FORCEPROP 1 LAST PACK_TYPE C0402
J 0
(-8950 5050);
DISPLAY 0.489362 (-8950 5050);
PAINT SKYBLUE (-8950 5050);
FORCEPROP 2 LAST CDS_LIB pure_quanta
J 0
(-9000 5250);
PAINT MONO (-9000 5250);
DISPLAY INVISIBLE (-9000 5250);
FORCEPROP 1 LAST PATH I14
J 0
(-8950 5400);
DISPLAY 0.978723 (-8950 5400);
PAINT WHITE (-8950 5400);
DISPLAY INVISIBLE (-8950 5400);
FORCEPROP 1 LAST PART_NUMBER CH622KMEB02
J 0
(-8950 5100);
DISPLAY 0.489362 (-8950 5100);
PAINT SKYBLUE (-8950 5100);
DISPLAY INVISIBLE (-8950 5100);
FORCEADD Q_CAP..1
(-8550 5250);
FORCEPROP 1 LAST LOCATION C251
J 0
(-8500 5350);
DISPLAY 0.489362 (-8500 5350);
PAINT SKYBLUE (-8500 5350);
FORCEPROP 2 LAST $SEC 1
J 0
(-8500 5450);
DISPLAY 0.680851 (-8500 5450);
PAINT MONO (-8500 5450);
DISPLAY INVISIBLE (-8500 5450);
FORCEPROP 2 LAST CDS_SEC 1
J 0
(-8500 5450);
DISPLAY 1.021277 (-8500 5450);
DISPLAY INVISIBLE (-8500 5450);
FORCEPROP 1 LASTPIN (-8550 5350) $PN 1
J 0
(-8540 5330);
DISPLAY 0.489362 (-8540 5330);
FORCEPROP 1 LASTPIN (-8550 5150) $PN 2
J 0
(-8540 5130);
DISPLAY 0.489362 (-8540 5130);
FORCEPROP 1 LAST MATERIAL X6S
J 0
(-8500 5150);
DISPLAY 0.489362 (-8500 5150);
PAINT SKYBLUE (-8500 5150);
FORCEPROP 1 LAST TOLERANCE 20%
J 0
(-8500 5200);
DISPLAY 0.489362 (-8500 5200);
PAINT SKYBLUE (-8500 5200);
FORCEPROP 1 LAST VALUE 22UF
J 0
(-8500 5300);
DISPLAY 0.489362 (-8500 5300);
PAINT SKYBLUE (-8500 5300);
FORCEPROP 1 LAST VOLTAGE 4V
J 0
(-8500 5250);
DISPLAY 0.489362 (-8500 5250);
PAINT SKYBLUE (-8500 5250);
FORCEPROP 1 LAST PACK_TYPE C0402
J 0
(-8500 5050);
DISPLAY 0.489362 (-8500 5050);
PAINT SKYBLUE (-8500 5050);
FORCEPROP 2 LAST CDS_LIB pure_quanta
J 0
(-8550 5250);
PAINT MONO (-8550 5250);
DISPLAY INVISIBLE (-8550 5250);
FORCEPROP 1 LAST PATH I15
J 0
(-8500 5400);
DISPLAY 0.978723 (-8500 5400);
PAINT WHITE (-8500 5400);
DISPLAY INVISIBLE (-8500 5400);
FORCEPROP 1 LAST PART_NUMBER CH622KMEB02
J 0
(-8500 5100);
DISPLAY 0.489362 (-8500 5100);
PAINT SKYBLUE (-8500 5100);
DISPLAY INVISIBLE (-8500 5100);
FORCEADD Q_CAP..1
(-8100 2075);
FORCEPROP 1 LAST LOCATION C2175
J 0
(-8050 2175);
DISPLAY 0.489362 (-8050 2175);
PAINT SKYBLUE (-8050 2175);
FORCEPROP 2 LAST $SEC 1
J 0
(-8050 2275);
DISPLAY 0.680851 (-8050 2275);
PAINT MONO (-8050 2275);
DISPLAY INVISIBLE (-8050 2275);
FORCEPROP 2 LAST CDS_SEC 1
J 0
(-8050 2275);
DISPLAY 1.021277 (-8050 2275);
DISPLAY INVISIBLE (-8050 2275);
FORCEPROP 1 LASTPIN (-8100 2175) $PN 1
J 0
(-8090 2155);
DISPLAY 0.489362 (-8090 2155);
FORCEPROP 1 LASTPIN (-8100 1975) $PN 2
J 0
(-8090 1955);
DISPLAY 0.489362 (-8090 1955);
FORCEPROP 1 LAST TOLERANCE 20%
J 0
(-8050 2025);
DISPLAY 0.489362 (-8050 2025);
PAINT SKYBLUE (-8050 2025);
FORCEPROP 1 LAST VALUE 22UF
J 0
(-8050 2125);
DISPLAY 0.489362 (-8050 2125);
PAINT SKYBLUE (-8050 2125);
FORCEPROP 1 LAST VOLTAGE 4V
J 0
(-8050 2075);
DISPLAY 0.489362 (-8050 2075);
PAINT SKYBLUE (-8050 2075);
FORCEPROP 1 LAST PACK_TYPE C0402
J 0
(-8050 1875);
DISPLAY 0.489362 (-8050 1875);
PAINT SKYBLUE (-8050 1875);
FORCEPROP 1 LAST MATERIAL X6S
J 0
(-8050 1975);
DISPLAY 0.489362 (-8050 1975);
PAINT SKYBLUE (-8050 1975);
FORCEPROP 2 LAST CDS_LIB pure_quanta
J 0
(-8100 2075);
PAINT MONO (-8100 2075);
DISPLAY INVISIBLE (-8100 2075);
FORCEPROP 1 LAST PATH I16
J 0
(-8050 2225);
DISPLAY 0.978723 (-8050 2225);
PAINT WHITE (-8050 2225);
DISPLAY INVISIBLE (-8050 2225);
FORCEPROP 1 LAST PART_NUMBER CH622KMEB02
J 0
(-8050 1925);
DISPLAY 0.489362 (-8050 1925);
PAINT SKYBLUE (-8050 1925);
DISPLAY INVISIBLE (-8050 1925);
FORCEADD Q_CAP..1
(-7650 2075);
FORCEPROP 1 LAST LOCATION C10179
J 0
(-7600 2175);
DISPLAY 0.489362 (-7600 2175);
PAINT SKYBLUE (-7600 2175);
FORCEPROP 2 LAST $SEC 1
J 0
(-7600 2275);
DISPLAY 0.680851 (-7600 2275);
PAINT MONO (-7600 2275);
DISPLAY INVISIBLE (-7600 2275);
FORCEPROP 2 LAST CDS_SEC 1
J 0
(-7600 2275);
DISPLAY 1.021277 (-7600 2275);
DISPLAY INVISIBLE (-7600 2275);
FORCEPROP 1 LASTPIN (-7650 2175) $PN 1
J 0
(-7640 2155);
DISPLAY 0.489362 (-7640 2155);
FORCEPROP 1 LASTPIN (-7650 1975) $PN 2
J 0
(-7640 1955);
DISPLAY 0.489362 (-7640 1955);
FORCEPROP 1 LAST MATERIAL X6S
J 0
(-7600 1975);
DISPLAY 0.489362 (-7600 1975);
PAINT SKYBLUE (-7600 1975);
FORCEPROP 1 LAST TOLERANCE 20%
J 0
(-7600 2025);
DISPLAY 0.489362 (-7600 2025);
PAINT SKYBLUE (-7600 2025);
FORCEPROP 1 LAST VALUE 22UF
J 0
(-7600 2125);
DISPLAY 0.489362 (-7600 2125);
PAINT SKYBLUE (-7600 2125);
FORCEPROP 1 LAST VOLTAGE 4V
J 0
(-7600 2075);
DISPLAY 0.489362 (-7600 2075);
PAINT SKYBLUE (-7600 2075);
FORCEPROP 1 LAST PACK_TYPE C0402
J 0
(-7600 1875);
DISPLAY 0.489362 (-7600 1875);
PAINT SKYBLUE (-7600 1875);
FORCEPROP 2 LAST CDS_LIB pure_quanta
J 0
(-7650 2075);
PAINT MONO (-7650 2075);
DISPLAY INVISIBLE (-7650 2075);
FORCEPROP 1 LAST PATH I17
J 0
(-7600 2225);
DISPLAY 0.978723 (-7600 2225);
PAINT WHITE (-7600 2225);
DISPLAY INVISIBLE (-7600 2225);
FORCEPROP 1 LAST PART_NUMBER CH622KMEB02
J 0
(-7600 1925);
DISPLAY 0.489362 (-7600 1925);
PAINT SKYBLUE (-7600 1925);
DISPLAY INVISIBLE (-7600 1925);
FORCEADD UNIVERSAL_GND..1
(-7200 1675);
FORCEPROP 3 LASTPIN (-7200 1725) SIG_NAME GND\g
J 0
(-7190 1735);
DISPLAY 0.659574 (-7190 1735);
PAINT MONO (-7190 1735);
DISPLAY INVISIBLE (-7190 1735);
FORCEPROP 2 LAST CDS_LIB pure_quanta_power
J 0
(-7200 1675);
PAINT MONO (-7200 1675);
DISPLAY INVISIBLE (-7200 1675);
FORCEPROP 1 LAST HDL_POWER GND
J 1
(-7175 1600);
DISPLAY 0.872340 (-7175 1600);
PAINT GREEN (-7175 1600);
DISPLAY INVISIBLE (-7175 1600);
FORCEPROP 1 LAST PATH I18
J 0
(-7125 1675);
DISPLAY 0.872340 (-7125 1675);
PAINT AQUA (-7125 1675);
DISPLAY INVISIBLE (-7125 1675);
FORCEADD Q_CAP..1
(-7200 2075);
FORCEPROP 1 LAST LOCATION C2183
J 0
(-7150 2175);
DISPLAY 0.489362 (-7150 2175);
PAINT SKYBLUE (-7150 2175);
FORCEPROP 2 LAST $SEC 1
J 0
(-7150 2275);
DISPLAY 0.680851 (-7150 2275);
PAINT MONO (-7150 2275);
DISPLAY INVISIBLE (-7150 2275);
FORCEPROP 2 LAST CDS_SEC 1
J 0
(-7150 2275);
DISPLAY 1.021277 (-7150 2275);
DISPLAY INVISIBLE (-7150 2275);
FORCEPROP 1 LASTPIN (-7200 2175) $PN 1
J 0
(-7190 2155);
DISPLAY 0.489362 (-7190 2155);
FORCEPROP 1 LASTPIN (-7200 1975) $PN 2
J 0
(-7190 1955);
DISPLAY 0.489362 (-7190 1955);
FORCEPROP 1 LAST MATERIAL X6S
J 0
(-7150 1975);
DISPLAY 0.489362 (-7150 1975);
PAINT SKYBLUE (-7150 1975);
FORCEPROP 1 LAST TOLERANCE 20%
J 0
(-7150 2025);
DISPLAY 0.489362 (-7150 2025);
PAINT SKYBLUE (-7150 2025);
FORCEPROP 1 LAST VALUE 22UF
J 0
(-7150 2125);
DISPLAY 0.489362 (-7150 2125);
PAINT SKYBLUE (-7150 2125);
FORCEPROP 1 LAST VOLTAGE 4V
J 0
(-7150 2075);
DISPLAY 0.489362 (-7150 2075);
PAINT SKYBLUE (-7150 2075);
FORCEPROP 1 LAST PACK_TYPE C0402
J 0
(-7150 1875);
DISPLAY 0.489362 (-7150 1875);
PAINT SKYBLUE (-7150 1875);
FORCEPROP 2 LAST CDS_LIB pure_quanta
J 0
(-7200 2075);
PAINT MONO (-7200 2075);
DISPLAY INVISIBLE (-7200 2075);
FORCEPROP 1 LAST PATH I19
J 0
(-7150 2225);
DISPLAY 0.978723 (-7150 2225);
PAINT WHITE (-7150 2225);
DISPLAY INVISIBLE (-7150 2225);
FORCEPROP 1 LAST PART_NUMBER CH622KMEB02
J 0
(-7150 1925);
DISPLAY 0.489362 (-7150 1925);
PAINT SKYBLUE (-7150 1925);
DISPLAY INVISIBLE (-7150 1925);
FORCEADD Q_CAP..1
(-8550 2075);
FORCEPROP 1 LAST LOCATION C2171
J 0
(-8500 2175);
DISPLAY 0.489362 (-8500 2175);
PAINT SKYBLUE (-8500 2175);
FORCEPROP 2 LAST $SEC 1
J 0
(-8500 2275);
DISPLAY 0.680851 (-8500 2275);
PAINT MONO (-8500 2275);
DISPLAY INVISIBLE (-8500 2275);
FORCEPROP 2 LAST CDS_SEC 1
J 0
(-8500 2275);
DISPLAY 1.021277 (-8500 2275);
DISPLAY INVISIBLE (-8500 2275);
FORCEPROP 1 LASTPIN (-8550 2175) $PN 1
J 0
(-8540 2155);
DISPLAY 0.489362 (-8540 2155);
FORCEPROP 1 LASTPIN (-8550 1975) $PN 2
J 0
(-8540 1955);
DISPLAY 0.489362 (-8540 1955);
FORCEPROP 1 LAST MATERIAL X6S
J 0
(-8500 1975);
DISPLAY 0.489362 (-8500 1975);
PAINT SKYBLUE (-8500 1975);
FORCEPROP 1 LAST TOLERANCE 20%
J 0
(-8500 2025);
DISPLAY 0.489362 (-8500 2025);
PAINT SKYBLUE (-8500 2025);
FORCEPROP 1 LAST VALUE 22UF
J 0
(-8500 2125);
DISPLAY 0.489362 (-8500 2125);
PAINT SKYBLUE (-8500 2125);
FORCEPROP 1 LAST VOLTAGE 4V
J 0
(-8500 2075);
DISPLAY 0.489362 (-8500 2075);
PAINT SKYBLUE (-8500 2075);
FORCEPROP 1 LAST PACK_TYPE C0402
J 0
(-8500 1875);
DISPLAY 0.489362 (-8500 1875);
PAINT SKYBLUE (-8500 1875);
FORCEPROP 2 LAST CDS_LIB pure_quanta
J 0
(-8550 2075);
PAINT MONO (-8550 2075);
DISPLAY INVISIBLE (-8550 2075);
FORCEPROP 1 LAST PATH I2
J 0
(-8500 2225);
DISPLAY 0.978723 (-8500 2225);
PAINT WHITE (-8500 2225);
DISPLAY INVISIBLE (-8500 2225);
FORCEPROP 1 LAST PART_NUMBER CH622KMEB02
J 0
(-8500 1925);
DISPLAY 0.489362 (-8500 1925);
PAINT SKYBLUE (-8500 1925);
DISPLAY INVISIBLE (-8500 1925);
FORCEADD Q_CAP..1
(-8100 2875);
FORCEPROP 1 LAST LOCATION C2174
J 0
(-8050 2975);
DISPLAY 0.489362 (-8050 2975);
PAINT SKYBLUE (-8050 2975);
FORCEPROP 2 LAST $SEC 1
J 0
(-8050 3075);
DISPLAY 0.680851 (-8050 3075);
PAINT MONO (-8050 3075);
DISPLAY INVISIBLE (-8050 3075);
FORCEPROP 2 LAST CDS_SEC 1
J 0
(-8050 3075);
DISPLAY 1.021277 (-8050 3075);
DISPLAY INVISIBLE (-8050 3075);
FORCEPROP 1 LASTPIN (-8100 2975) $PN 1
J 0
(-8090 2955);
DISPLAY 0.489362 (-8090 2955);
FORCEPROP 1 LASTPIN (-8100 2775) $PN 2
J 0
(-8090 2755);
DISPLAY 0.489362 (-8090 2755);
FORCEPROP 1 LAST MATERIAL X6S
J 0
(-8050 2775);
DISPLAY 0.489362 (-8050 2775);
PAINT SKYBLUE (-8050 2775);
FORCEPROP 1 LAST TOLERANCE 20%
J 0
(-8050 2825);
DISPLAY 0.489362 (-8050 2825);
PAINT SKYBLUE (-8050 2825);
FORCEPROP 1 LAST VALUE 22UF
J 0
(-8050 2925);
DISPLAY 0.489362 (-8050 2925);
PAINT SKYBLUE (-8050 2925);
FORCEPROP 1 LAST VOLTAGE 4V
J 0
(-8050 2875);
DISPLAY 0.489362 (-8050 2875);
PAINT SKYBLUE (-8050 2875);
FORCEPROP 1 LAST PACK_TYPE C0402
J 0
(-8050 2675);
DISPLAY 0.489362 (-8050 2675);
PAINT SKYBLUE (-8050 2675);
FORCEPROP 2 LAST CDS_LIB pure_quanta
J 0
(-8100 2875);
PAINT MONO (-8100 2875);
DISPLAY INVISIBLE (-8100 2875);
FORCEPROP 1 LAST PATH I20
J 0
(-8050 3025);
DISPLAY 0.978723 (-8050 3025);
PAINT WHITE (-8050 3025);
DISPLAY INVISIBLE (-8050 3025);
FORCEPROP 1 LAST PART_NUMBER CH622KMEB02
J 0
(-8050 2725);
DISPLAY 0.489362 (-8050 2725);
PAINT SKYBLUE (-8050 2725);
DISPLAY INVISIBLE (-8050 2725);
FORCEADD Q_CAP..1
(-7650 2875);
FORCEPROP 1 LAST LOCATION C2178
J 0
(-7600 2975);
DISPLAY 0.489362 (-7600 2975);
PAINT SKYBLUE (-7600 2975);
FORCEPROP 2 LAST $SEC 1
J 0
(-7600 3075);
DISPLAY 0.680851 (-7600 3075);
PAINT MONO (-7600 3075);
DISPLAY INVISIBLE (-7600 3075);
FORCEPROP 2 LAST CDS_SEC 1
J 0
(-7600 3075);
DISPLAY 1.021277 (-7600 3075);
DISPLAY INVISIBLE (-7600 3075);
FORCEPROP 1 LASTPIN (-7650 2975) $PN 1
J 0
(-7640 2955);
DISPLAY 0.489362 (-7640 2955);
FORCEPROP 1 LASTPIN (-7650 2775) $PN 2
J 0
(-7640 2755);
DISPLAY 0.489362 (-7640 2755);
FORCEPROP 1 LAST MATERIAL X6S
J 0
(-7600 2775);
DISPLAY 0.489362 (-7600 2775);
PAINT SKYBLUE (-7600 2775);
FORCEPROP 1 LAST TOLERANCE 20%
J 0
(-7600 2825);
DISPLAY 0.489362 (-7600 2825);
PAINT SKYBLUE (-7600 2825);
FORCEPROP 1 LAST VALUE 22UF
J 0
(-7600 2925);
DISPLAY 0.489362 (-7600 2925);
PAINT SKYBLUE (-7600 2925);
FORCEPROP 1 LAST VOLTAGE 4V
J 0
(-7600 2875);
DISPLAY 0.489362 (-7600 2875);
PAINT SKYBLUE (-7600 2875);
FORCEPROP 1 LAST PACK_TYPE C0402
J 0
(-7600 2675);
DISPLAY 0.489362 (-7600 2675);
PAINT SKYBLUE (-7600 2675);
FORCEPROP 2 LAST CDS_LIB pure_quanta
J 0
(-7650 2875);
PAINT MONO (-7650 2875);
DISPLAY INVISIBLE (-7650 2875);
FORCEPROP 1 LAST PATH I21
J 0
(-7600 3025);
DISPLAY 0.978723 (-7600 3025);
PAINT WHITE (-7600 3025);
DISPLAY INVISIBLE (-7600 3025);
FORCEPROP 1 LAST PART_NUMBER CH622KMEB02
J 0
(-7600 2725);
DISPLAY 0.489362 (-7600 2725);
PAINT SKYBLUE (-7600 2725);
DISPLAY INVISIBLE (-7600 2725);
FORCEADD Q_CAP..1
(-8100 3675);
FORCEPROP 1 LAST LOCATION C2173
J 0
(-8050 3775);
DISPLAY 0.489362 (-8050 3775);
PAINT SKYBLUE (-8050 3775);
FORCEPROP 2 LAST $SEC 1
J 0
(-8050 3875);
DISPLAY 0.680851 (-8050 3875);
PAINT MONO (-8050 3875);
DISPLAY INVISIBLE (-8050 3875);
FORCEPROP 2 LAST CDS_SEC 1
J 0
(-8050 3875);
DISPLAY 1.021277 (-8050 3875);
DISPLAY INVISIBLE (-8050 3875);
FORCEPROP 1 LASTPIN (-8100 3775) $PN 1
J 0
(-8090 3755);
DISPLAY 0.489362 (-8090 3755);
FORCEPROP 1 LASTPIN (-8100 3575) $PN 2
J 0
(-8090 3555);
DISPLAY 0.489362 (-8090 3555);
FORCEPROP 1 LAST MATERIAL X6S
J 0
(-8050 3575);
DISPLAY 0.489362 (-8050 3575);
PAINT SKYBLUE (-8050 3575);
FORCEPROP 1 LAST TOLERANCE 20%
J 0
(-8050 3625);
DISPLAY 0.489362 (-8050 3625);
PAINT SKYBLUE (-8050 3625);
FORCEPROP 1 LAST VALUE 22UF
J 0
(-8050 3725);
DISPLAY 0.489362 (-8050 3725);
PAINT SKYBLUE (-8050 3725);
FORCEPROP 1 LAST VOLTAGE 4V
J 0
(-8050 3675);
DISPLAY 0.489362 (-8050 3675);
PAINT SKYBLUE (-8050 3675);
FORCEPROP 1 LAST PACK_TYPE C0402
J 0
(-8050 3475);
DISPLAY 0.489362 (-8050 3475);
PAINT SKYBLUE (-8050 3475);
FORCEPROP 2 LAST CDS_LIB pure_quanta
J 0
(-8100 3675);
PAINT MONO (-8100 3675);
DISPLAY INVISIBLE (-8100 3675);
FORCEPROP 1 LAST PATH I22
J 0
(-8050 3825);
DISPLAY 0.978723 (-8050 3825);
PAINT WHITE (-8050 3825);
DISPLAY INVISIBLE (-8050 3825);
FORCEPROP 1 LAST PART_NUMBER CH622KMEB02
J 0
(-8050 3525);
DISPLAY 0.489362 (-8050 3525);
PAINT SKYBLUE (-8050 3525);
DISPLAY INVISIBLE (-8050 3525);
FORCEADD Q_CAP..1
(-7650 3675);
FORCEPROP 1 LAST LOCATION C2177
J 0
(-7600 3775);
DISPLAY 0.489362 (-7600 3775);
PAINT SKYBLUE (-7600 3775);
FORCEPROP 2 LAST $SEC 1
J 0
(-7600 3875);
DISPLAY 0.680851 (-7600 3875);
PAINT MONO (-7600 3875);
DISPLAY INVISIBLE (-7600 3875);
FORCEPROP 2 LAST CDS_SEC 1
J 0
(-7600 3875);
DISPLAY 1.021277 (-7600 3875);
DISPLAY INVISIBLE (-7600 3875);
FORCEPROP 1 LASTPIN (-7650 3775) $PN 1
J 0
(-7640 3755);
DISPLAY 0.489362 (-7640 3755);
FORCEPROP 1 LASTPIN (-7650 3575) $PN 2
J 0
(-7640 3555);
DISPLAY 0.489362 (-7640 3555);
FORCEPROP 1 LAST MATERIAL X6S
J 0
(-7600 3575);
DISPLAY 0.489362 (-7600 3575);
PAINT SKYBLUE (-7600 3575);
FORCEPROP 1 LAST TOLERANCE 20%
J 0
(-7600 3625);
DISPLAY 0.489362 (-7600 3625);
PAINT SKYBLUE (-7600 3625);
FORCEPROP 1 LAST VALUE 22UF
J 0
(-7600 3725);
DISPLAY 0.489362 (-7600 3725);
PAINT SKYBLUE (-7600 3725);
FORCEPROP 1 LAST VOLTAGE 4V
J 0
(-7600 3675);
DISPLAY 0.489362 (-7600 3675);
PAINT SKYBLUE (-7600 3675);
FORCEPROP 1 LAST PACK_TYPE C0402
J 0
(-7600 3475);
DISPLAY 0.489362 (-7600 3475);
PAINT SKYBLUE (-7600 3475);
FORCEPROP 2 LAST CDS_LIB pure_quanta
J 0
(-7650 3675);
PAINT MONO (-7650 3675);
DISPLAY INVISIBLE (-7650 3675);
FORCEPROP 1 LAST PATH I23
J 0
(-7600 3825);
DISPLAY 0.978723 (-7600 3825);
PAINT WHITE (-7600 3825);
DISPLAY INVISIBLE (-7600 3825);
FORCEPROP 1 LAST PART_NUMBER CH622KMEB02
J 0
(-7600 3525);
DISPLAY 0.489362 (-7600 3525);
PAINT SKYBLUE (-7600 3525);
DISPLAY INVISIBLE (-7600 3525);
FORCEADD Q_CAP..1
(-7200 2875);
FORCEPROP 1 LAST LOCATION C2182
J 0
(-7150 2975);
DISPLAY 0.489362 (-7150 2975);
PAINT SKYBLUE (-7150 2975);
FORCEPROP 2 LAST $SEC 1
J 0
(-7150 3075);
DISPLAY 0.680851 (-7150 3075);
PAINT MONO (-7150 3075);
DISPLAY INVISIBLE (-7150 3075);
FORCEPROP 2 LAST CDS_SEC 1
J 0
(-7150 3075);
DISPLAY 1.021277 (-7150 3075);
DISPLAY INVISIBLE (-7150 3075);
FORCEPROP 1 LASTPIN (-7200 2975) $PN 1
J 0
(-7190 2955);
DISPLAY 0.489362 (-7190 2955);
FORCEPROP 1 LASTPIN (-7200 2775) $PN 2
J 0
(-7190 2755);
DISPLAY 0.489362 (-7190 2755);
FORCEPROP 1 LAST MATERIAL X6S
J 0
(-7150 2775);
DISPLAY 0.489362 (-7150 2775);
PAINT SKYBLUE (-7150 2775);
FORCEPROP 1 LAST TOLERANCE 20%
J 0
(-7150 2825);
DISPLAY 0.489362 (-7150 2825);
PAINT SKYBLUE (-7150 2825);
FORCEPROP 1 LAST VALUE 22UF
J 0
(-7150 2925);
DISPLAY 0.489362 (-7150 2925);
PAINT SKYBLUE (-7150 2925);
FORCEPROP 1 LAST VOLTAGE 4V
J 0
(-7150 2875);
DISPLAY 0.489362 (-7150 2875);
PAINT SKYBLUE (-7150 2875);
FORCEPROP 1 LAST PACK_TYPE C0402
J 0
(-7150 2675);
DISPLAY 0.489362 (-7150 2675);
PAINT SKYBLUE (-7150 2675);
FORCEPROP 2 LAST CDS_LIB pure_quanta
J 0
(-7200 2875);
PAINT MONO (-7200 2875);
DISPLAY INVISIBLE (-7200 2875);
FORCEPROP 1 LAST PATH I24
J 0
(-7150 3025);
DISPLAY 0.978723 (-7150 3025);
PAINT WHITE (-7150 3025);
DISPLAY INVISIBLE (-7150 3025);
FORCEPROP 1 LAST PART_NUMBER CH622KMEB02
J 0
(-7150 2725);
DISPLAY 0.489362 (-7150 2725);
PAINT SKYBLUE (-7150 2725);
DISPLAY INVISIBLE (-7150 2725);
FORCEADD Q_CAP..1
(-7200 3675);
FORCEPROP 1 LAST LOCATION C2181
J 0
(-7150 3775);
DISPLAY 0.489362 (-7150 3775);
PAINT SKYBLUE (-7150 3775);
FORCEPROP 2 LAST $SEC 1
J 0
(-7150 3875);
DISPLAY 0.680851 (-7150 3875);
PAINT MONO (-7150 3875);
DISPLAY INVISIBLE (-7150 3875);
FORCEPROP 2 LAST CDS_SEC 1
J 0
(-7150 3875);
DISPLAY 1.021277 (-7150 3875);
DISPLAY INVISIBLE (-7150 3875);
FORCEPROP 1 LASTPIN (-7200 3775) $PN 1
J 0
(-7190 3755);
DISPLAY 0.489362 (-7190 3755);
FORCEPROP 1 LASTPIN (-7200 3575) $PN 2
J 0
(-7190 3555);
DISPLAY 0.489362 (-7190 3555);
FORCEPROP 1 LAST MATERIAL X6S
J 0
(-7150 3575);
DISPLAY 0.489362 (-7150 3575);
PAINT SKYBLUE (-7150 3575);
FORCEPROP 1 LAST TOLERANCE 20%
J 0
(-7150 3625);
DISPLAY 0.489362 (-7150 3625);
PAINT SKYBLUE (-7150 3625);
FORCEPROP 1 LAST VALUE 22UF
J 0
(-7150 3725);
DISPLAY 0.489362 (-7150 3725);
PAINT SKYBLUE (-7150 3725);
FORCEPROP 1 LAST VOLTAGE 4V
J 0
(-7150 3675);
DISPLAY 0.489362 (-7150 3675);
PAINT SKYBLUE (-7150 3675);
FORCEPROP 1 LAST PACK_TYPE C0402
J 0
(-7150 3475);
DISPLAY 0.489362 (-7150 3475);
PAINT SKYBLUE (-7150 3475);
FORCEPROP 2 LAST CDS_LIB pure_quanta
J 0
(-7200 3675);
PAINT MONO (-7200 3675);
DISPLAY INVISIBLE (-7200 3675);
FORCEPROP 1 LAST PATH I25
J 0
(-7150 3825);
DISPLAY 0.978723 (-7150 3825);
PAINT WHITE (-7150 3825);
DISPLAY INVISIBLE (-7150 3825);
FORCEPROP 1 LAST PART_NUMBER CH622KMEB02
J 0
(-7150 3525);
DISPLAY 0.489362 (-7150 3525);
PAINT SKYBLUE (-7150 3525);
DISPLAY INVISIBLE (-7150 3525);
FORCEADD Q_CAP..1
(-6750 2875);
FORCEPROP 1 LAST LOCATION C2186
J 0
(-6700 2975);
DISPLAY 0.489362 (-6700 2975);
PAINT SKYBLUE (-6700 2975);
FORCEPROP 2 LAST $SEC 1
J 0
(-6700 3075);
DISPLAY 0.680851 (-6700 3075);
PAINT MONO (-6700 3075);
DISPLAY INVISIBLE (-6700 3075);
FORCEPROP 2 LAST CDS_SEC 1
J 0
(-6700 3075);
DISPLAY 1.021277 (-6700 3075);
DISPLAY INVISIBLE (-6700 3075);
FORCEPROP 1 LASTPIN (-6750 2975) $PN 1
J 0
(-6740 2955);
DISPLAY 0.489362 (-6740 2955);
FORCEPROP 1 LASTPIN (-6750 2775) $PN 2
J 0
(-6740 2755);
DISPLAY 0.489362 (-6740 2755);
FORCEPROP 1 LAST MATERIAL X6S
J 0
(-6700 2775);
DISPLAY 0.489362 (-6700 2775);
PAINT SKYBLUE (-6700 2775);
FORCEPROP 1 LAST TOLERANCE 20%
J 0
(-6700 2825);
DISPLAY 0.489362 (-6700 2825);
PAINT SKYBLUE (-6700 2825);
FORCEPROP 1 LAST VALUE 22UF
J 0
(-6700 2925);
DISPLAY 0.489362 (-6700 2925);
PAINT SKYBLUE (-6700 2925);
FORCEPROP 1 LAST VOLTAGE 4V
J 0
(-6700 2875);
DISPLAY 0.489362 (-6700 2875);
PAINT SKYBLUE (-6700 2875);
FORCEPROP 1 LAST PACK_TYPE C0402
J 0
(-6700 2675);
DISPLAY 0.489362 (-6700 2675);
PAINT SKYBLUE (-6700 2675);
FORCEPROP 2 LAST CDS_LIB pure_quanta
J 0
(-6750 2875);
PAINT MONO (-6750 2875);
DISPLAY INVISIBLE (-6750 2875);
FORCEPROP 1 LAST PATH I26
J 0
(-6700 3025);
DISPLAY 0.978723 (-6700 3025);
PAINT WHITE (-6700 3025);
DISPLAY INVISIBLE (-6700 3025);
FORCEPROP 1 LAST PART_NUMBER CH622KMEB02
J 0
(-6700 2725);
DISPLAY 0.489362 (-6700 2725);
PAINT SKYBLUE (-6700 2725);
DISPLAY INVISIBLE (-6700 2725);
FORCEADD Q_CAP..1
(-6300 2875);
FORCEPROP 1 LAST LOCATION C2190
J 0
(-6250 2975);
DISPLAY 0.489362 (-6250 2975);
PAINT SKYBLUE (-6250 2975);
FORCEPROP 2 LAST $SEC 1
J 0
(-6250 3075);
DISPLAY 0.680851 (-6250 3075);
PAINT MONO (-6250 3075);
DISPLAY INVISIBLE (-6250 3075);
FORCEPROP 2 LAST CDS_SEC 1
J 0
(-6250 3075);
DISPLAY 1.021277 (-6250 3075);
DISPLAY INVISIBLE (-6250 3075);
FORCEPROP 1 LASTPIN (-6300 2975) $PN 1
J 0
(-6290 2955);
DISPLAY 0.489362 (-6290 2955);
FORCEPROP 1 LASTPIN (-6300 2775) $PN 2
J 0
(-6290 2755);
DISPLAY 0.489362 (-6290 2755);
FORCEPROP 1 LAST MATERIAL X6S
J 0
(-6250 2775);
DISPLAY 0.489362 (-6250 2775);
PAINT SKYBLUE (-6250 2775);
FORCEPROP 1 LAST TOLERANCE 20%
J 0
(-6250 2825);
DISPLAY 0.489362 (-6250 2825);
PAINT SKYBLUE (-6250 2825);
FORCEPROP 1 LAST VALUE 22UF
J 0
(-6250 2925);
DISPLAY 0.489362 (-6250 2925);
PAINT SKYBLUE (-6250 2925);
FORCEPROP 1 LAST VOLTAGE 4V
J 0
(-6250 2875);
DISPLAY 0.489362 (-6250 2875);
PAINT SKYBLUE (-6250 2875);
FORCEPROP 1 LAST PACK_TYPE C0402
J 0
(-6250 2675);
DISPLAY 0.489362 (-6250 2675);
PAINT SKYBLUE (-6250 2675);
FORCEPROP 2 LAST CDS_LIB pure_quanta
J 0
(-6300 2875);
PAINT MONO (-6300 2875);
DISPLAY INVISIBLE (-6300 2875);
FORCEPROP 1 LAST PATH I27
J 0
(-6250 3025);
DISPLAY 0.978723 (-6250 3025);
PAINT WHITE (-6250 3025);
DISPLAY INVISIBLE (-6250 3025);
FORCEPROP 1 LAST PART_NUMBER CH622KMEB02
J 0
(-6250 2725);
DISPLAY 0.489362 (-6250 2725);
PAINT SKYBLUE (-6250 2725);
DISPLAY INVISIBLE (-6250 2725);
FORCEADD Q_CAP..1
(-6750 3675);
FORCEPROP 1 LAST LOCATION C2185
J 0
(-6700 3775);
DISPLAY 0.489362 (-6700 3775);
PAINT SKYBLUE (-6700 3775);
FORCEPROP 2 LAST $SEC 1
J 0
(-6700 3875);
DISPLAY 0.680851 (-6700 3875);
PAINT MONO (-6700 3875);
DISPLAY INVISIBLE (-6700 3875);
FORCEPROP 2 LAST CDS_SEC 1
J 0
(-6700 3875);
DISPLAY 1.021277 (-6700 3875);
DISPLAY INVISIBLE (-6700 3875);
FORCEPROP 1 LASTPIN (-6750 3775) $PN 1
J 0
(-6740 3755);
DISPLAY 0.489362 (-6740 3755);
FORCEPROP 1 LASTPIN (-6750 3575) $PN 2
J 0
(-6740 3555);
DISPLAY 0.489362 (-6740 3555);
FORCEPROP 1 LAST MATERIAL X6S
J 0
(-6700 3575);
DISPLAY 0.489362 (-6700 3575);
PAINT SKYBLUE (-6700 3575);
FORCEPROP 1 LAST TOLERANCE 20%
J 0
(-6700 3625);
DISPLAY 0.489362 (-6700 3625);
PAINT SKYBLUE (-6700 3625);
FORCEPROP 1 LAST VALUE 22UF
J 0
(-6700 3725);
DISPLAY 0.489362 (-6700 3725);
PAINT SKYBLUE (-6700 3725);
FORCEPROP 1 LAST VOLTAGE 4V
J 0
(-6700 3675);
DISPLAY 0.489362 (-6700 3675);
PAINT SKYBLUE (-6700 3675);
FORCEPROP 1 LAST PACK_TYPE C0402
J 0
(-6700 3475);
DISPLAY 0.489362 (-6700 3475);
PAINT SKYBLUE (-6700 3475);
FORCEPROP 2 LAST CDS_LIB pure_quanta
J 0
(-6750 3675);
PAINT MONO (-6750 3675);
DISPLAY INVISIBLE (-6750 3675);
FORCEPROP 1 LAST PATH I28
J 0
(-6700 3825);
DISPLAY 0.978723 (-6700 3825);
PAINT WHITE (-6700 3825);
DISPLAY INVISIBLE (-6700 3825);
FORCEPROP 1 LAST PART_NUMBER CH622KMEB02
J 0
(-6700 3525);
DISPLAY 0.489362 (-6700 3525);
PAINT SKYBLUE (-6700 3525);
DISPLAY INVISIBLE (-6700 3525);
FORCEADD Q_CAP..1
(-6300 3675);
FORCEPROP 1 LAST LOCATION C2189
J 0
(-6250 3775);
DISPLAY 0.489362 (-6250 3775);
PAINT SKYBLUE (-6250 3775);
FORCEPROP 2 LAST $SEC 1
J 0
(-6250 3875);
DISPLAY 0.680851 (-6250 3875);
PAINT MONO (-6250 3875);
DISPLAY INVISIBLE (-6250 3875);
FORCEPROP 2 LAST CDS_SEC 1
J 0
(-6250 3875);
DISPLAY 1.021277 (-6250 3875);
DISPLAY INVISIBLE (-6250 3875);
FORCEPROP 1 LASTPIN (-6300 3775) $PN 1
J 0
(-6290 3755);
DISPLAY 0.489362 (-6290 3755);
FORCEPROP 1 LASTPIN (-6300 3575) $PN 2
J 0
(-6290 3555);
DISPLAY 0.489362 (-6290 3555);
FORCEPROP 1 LAST MATERIAL X6S
J 0
(-6250 3575);
DISPLAY 0.489362 (-6250 3575);
PAINT SKYBLUE (-6250 3575);
FORCEPROP 1 LAST TOLERANCE 20%
J 0
(-6250 3625);
DISPLAY 0.489362 (-6250 3625);
PAINT SKYBLUE (-6250 3625);
FORCEPROP 1 LAST VALUE 22UF
J 0
(-6250 3725);
DISPLAY 0.489362 (-6250 3725);
PAINT SKYBLUE (-6250 3725);
FORCEPROP 1 LAST VOLTAGE 4V
J 0
(-6250 3675);
DISPLAY 0.489362 (-6250 3675);
PAINT SKYBLUE (-6250 3675);
FORCEPROP 1 LAST PACK_TYPE C0402
J 0
(-6250 3475);
DISPLAY 0.489362 (-6250 3475);
PAINT SKYBLUE (-6250 3475);
FORCEPROP 2 LAST CDS_LIB pure_quanta
J 0
(-6300 3675);
PAINT MONO (-6300 3675);
DISPLAY INVISIBLE (-6300 3675);
FORCEPROP 1 LAST PATH I29
J 0
(-6250 3825);
DISPLAY 0.978723 (-6250 3825);
PAINT WHITE (-6250 3825);
DISPLAY INVISIBLE (-6250 3825);
FORCEPROP 1 LAST PART_NUMBER CH622KMEB02
J 0
(-6250 3525);
DISPLAY 0.489362 (-6250 3525);
PAINT SKYBLUE (-6250 3525);
DISPLAY INVISIBLE (-6250 3525);
FORCEADD UNIVERSAL_POWER..1
(-9000 2350);
FORCEPROP 3 LASTPIN (-9000 2300) SIG_NAME PVDDCR_CPU0_P0\g
J 0
(-8990 2310);
DISPLAY 0.659574 (-8990 2310);
PAINT MONO (-8990 2310);
DISPLAY INVISIBLE (-8990 2310);
FORCEPROP 1 LAST HDL_POWER PVDDCR_CPU0_P0
J 1
(-9000 2400);
DISPLAY 0.489362 (-9000 2400);
PAINT GREEN (-9000 2400);
FORCEPROP 2 LAST CDS_LIB pure_quanta_power
J 0
(-9000 2350);
DISPLAY INVISIBLE (-9000 2350);
FORCEPROP 1 LAST PATH I3
J 0
(-8950 2375);
DISPLAY 0.872340 (-8950 2375);
PAINT AQUA (-8950 2375);
DISPLAY INVISIBLE (-8950 2375);
FORCEADD Q_CAP..1
(-4425 2075);
FORCEPROP 1 LAST LOCATION C2205
J 0
(-4375 2175);
DISPLAY 0.489362 (-4375 2175);
PAINT SKYBLUE (-4375 2175);
FORCEPROP 2 LAST $SEC 1
J 0
(-4375 2275);
DISPLAY 0.680851 (-4375 2275);
PAINT MONO (-4375 2275);
DISPLAY INVISIBLE (-4375 2275);
FORCEPROP 2 LAST CDS_SEC 1
J 0
(-4375 2275);
DISPLAY 1.021277 (-4375 2275);
DISPLAY INVISIBLE (-4375 2275);
FORCEPROP 1 LASTPIN (-4425 2175) $PN 1
J 0
(-4415 2155);
DISPLAY 0.489362 (-4415 2155);
FORCEPROP 1 LASTPIN (-4425 1975) $PN 2
J 0
(-4415 1955);
DISPLAY 0.489362 (-4415 1955);
FORCEPROP 1 LAST MATERIAL X6S
J 0
(-4375 1975);
DISPLAY 0.489362 (-4375 1975);
PAINT SKYBLUE (-4375 1975);
FORCEPROP 1 LAST TOLERANCE 20%
J 0
(-4375 2025);
DISPLAY 0.489362 (-4375 2025);
PAINT SKYBLUE (-4375 2025);
FORCEPROP 1 LAST VALUE 22UF
J 0
(-4375 2125);
DISPLAY 0.489362 (-4375 2125);
PAINT SKYBLUE (-4375 2125);
FORCEPROP 1 LAST VOLTAGE 4V
J 0
(-4375 2075);
DISPLAY 0.489362 (-4375 2075);
PAINT SKYBLUE (-4375 2075);
FORCEPROP 1 LAST PACK_TYPE C0402
J 0
(-4375 1875);
DISPLAY 0.489362 (-4375 1875);
PAINT SKYBLUE (-4375 1875);
FORCEPROP 2 LAST CDS_LIB pure_quanta
J 0
(-4425 2075);
PAINT MONO (-4425 2075);
DISPLAY INVISIBLE (-4425 2075);
FORCEPROP 1 LAST PATH I30
J 0
(-4375 2225);
DISPLAY 0.978723 (-4375 2225);
PAINT WHITE (-4375 2225);
DISPLAY INVISIBLE (-4375 2225);
FORCEPROP 1 LAST PART_NUMBER CH622KMEB02
J 0
(-4375 1925);
DISPLAY 0.489362 (-4375 1925);
PAINT SKYBLUE (-4375 1925);
DISPLAY INVISIBLE (-4375 1925);
FORCEADD Q_CAP..1
(-5850 2875);
FORCEPROP 1 LAST LOCATION C2193
J 0
(-5800 2975);
DISPLAY 0.489362 (-5800 2975);
PAINT SKYBLUE (-5800 2975);
FORCEPROP 2 LAST $SEC 1
J 0
(-5800 3075);
DISPLAY 0.680851 (-5800 3075);
PAINT MONO (-5800 3075);
DISPLAY INVISIBLE (-5800 3075);
FORCEPROP 2 LAST CDS_SEC 1
J 0
(-5800 3075);
DISPLAY 1.021277 (-5800 3075);
DISPLAY INVISIBLE (-5800 3075);
FORCEPROP 1 LASTPIN (-5850 2975) $PN 1
J 0
(-5840 2955);
DISPLAY 0.489362 (-5840 2955);
FORCEPROP 1 LASTPIN (-5850 2775) $PN 2
J 0
(-5840 2755);
DISPLAY 0.489362 (-5840 2755);
FORCEPROP 1 LAST MATERIAL X6S
J 0
(-5800 2775);
DISPLAY 0.489362 (-5800 2775);
PAINT SKYBLUE (-5800 2775);
FORCEPROP 1 LAST TOLERANCE 20%
J 0
(-5800 2825);
DISPLAY 0.489362 (-5800 2825);
PAINT SKYBLUE (-5800 2825);
FORCEPROP 1 LAST VALUE 22UF
J 0
(-5800 2925);
DISPLAY 0.489362 (-5800 2925);
PAINT SKYBLUE (-5800 2925);
FORCEPROP 1 LAST VOLTAGE 4V
J 0
(-5800 2875);
DISPLAY 0.489362 (-5800 2875);
PAINT SKYBLUE (-5800 2875);
FORCEPROP 1 LAST PACK_TYPE C0402
J 0
(-5800 2675);
DISPLAY 0.489362 (-5800 2675);
PAINT SKYBLUE (-5800 2675);
FORCEPROP 2 LAST CDS_LIB pure_quanta
J 0
(-5850 2875);
PAINT MONO (-5850 2875);
DISPLAY INVISIBLE (-5850 2875);
FORCEPROP 1 LAST PATH I31
J 0
(-5800 3025);
DISPLAY 0.978723 (-5800 3025);
PAINT WHITE (-5800 3025);
DISPLAY INVISIBLE (-5800 3025);
FORCEPROP 1 LAST PART_NUMBER CH622KMEB02
J 0
(-5800 2725);
DISPLAY 0.489362 (-5800 2725);
PAINT SKYBLUE (-5800 2725);
DISPLAY INVISIBLE (-5800 2725);
FORCEADD Q_CAP..1
(-5400 2875);
FORCEPROP 1 LAST LOCATION C2196
J 0
(-5350 2975);
DISPLAY 0.489362 (-5350 2975);
PAINT SKYBLUE (-5350 2975);
FORCEPROP 2 LAST $SEC 1
J 0
(-5350 3075);
DISPLAY 0.680851 (-5350 3075);
PAINT MONO (-5350 3075);
DISPLAY INVISIBLE (-5350 3075);
FORCEPROP 2 LAST CDS_SEC 1
J 0
(-5350 3075);
DISPLAY 1.021277 (-5350 3075);
DISPLAY INVISIBLE (-5350 3075);
FORCEPROP 1 LASTPIN (-5400 2975) $PN 1
J 0
(-5390 2955);
DISPLAY 0.489362 (-5390 2955);
FORCEPROP 1 LASTPIN (-5400 2775) $PN 2
J 0
(-5390 2755);
DISPLAY 0.489362 (-5390 2755);
FORCEPROP 1 LAST MATERIAL X6S
J 0
(-5350 2775);
DISPLAY 0.489362 (-5350 2775);
PAINT SKYBLUE (-5350 2775);
FORCEPROP 1 LAST TOLERANCE 20%
J 0
(-5350 2825);
DISPLAY 0.489362 (-5350 2825);
PAINT SKYBLUE (-5350 2825);
FORCEPROP 1 LAST VALUE 22UF
J 0
(-5350 2925);
DISPLAY 0.489362 (-5350 2925);
PAINT SKYBLUE (-5350 2925);
FORCEPROP 1 LAST VOLTAGE 4V
J 0
(-5350 2875);
DISPLAY 0.489362 (-5350 2875);
PAINT SKYBLUE (-5350 2875);
FORCEPROP 1 LAST PACK_TYPE C0402
J 0
(-5350 2675);
DISPLAY 0.489362 (-5350 2675);
PAINT SKYBLUE (-5350 2675);
FORCEPROP 2 LAST CDS_LIB pure_quanta
J 0
(-5400 2875);
PAINT MONO (-5400 2875);
DISPLAY INVISIBLE (-5400 2875);
FORCEPROP 1 LAST PATH I32
J 0
(-5350 3025);
DISPLAY 0.978723 (-5350 3025);
PAINT WHITE (-5350 3025);
DISPLAY INVISIBLE (-5350 3025);
FORCEPROP 1 LAST PART_NUMBER CH622KMEB02
J 0
(-5350 2725);
DISPLAY 0.489362 (-5350 2725);
PAINT SKYBLUE (-5350 2725);
DISPLAY INVISIBLE (-5350 2725);
FORCEADD Q_CAP..1
(-5850 3675);
FORCEPROP 1 LAST LOCATION C2192
J 0
(-5800 3775);
DISPLAY 0.489362 (-5800 3775);
PAINT SKYBLUE (-5800 3775);
FORCEPROP 2 LAST $SEC 1
J 0
(-5800 3875);
DISPLAY 0.680851 (-5800 3875);
PAINT MONO (-5800 3875);
DISPLAY INVISIBLE (-5800 3875);
FORCEPROP 2 LAST CDS_SEC 1
J 0
(-5800 3875);
DISPLAY 1.021277 (-5800 3875);
DISPLAY INVISIBLE (-5800 3875);
FORCEPROP 1 LASTPIN (-5850 3775) $PN 1
J 0
(-5840 3755);
DISPLAY 0.489362 (-5840 3755);
FORCEPROP 1 LASTPIN (-5850 3575) $PN 2
J 0
(-5840 3555);
DISPLAY 0.489362 (-5840 3555);
FORCEPROP 1 LAST MATERIAL X6S
J 0
(-5800 3575);
DISPLAY 0.489362 (-5800 3575);
PAINT SKYBLUE (-5800 3575);
FORCEPROP 1 LAST TOLERANCE 20%
J 0
(-5800 3625);
DISPLAY 0.489362 (-5800 3625);
PAINT SKYBLUE (-5800 3625);
FORCEPROP 1 LAST VALUE 22UF
J 0
(-5800 3725);
DISPLAY 0.489362 (-5800 3725);
PAINT SKYBLUE (-5800 3725);
FORCEPROP 1 LAST VOLTAGE 4V
J 0
(-5800 3675);
DISPLAY 0.489362 (-5800 3675);
PAINT SKYBLUE (-5800 3675);
FORCEPROP 1 LAST PACK_TYPE C0402
J 0
(-5800 3475);
DISPLAY 0.489362 (-5800 3475);
PAINT SKYBLUE (-5800 3475);
FORCEPROP 2 LAST CDS_LIB pure_quanta
J 0
(-5850 3675);
PAINT MONO (-5850 3675);
DISPLAY INVISIBLE (-5850 3675);
FORCEPROP 1 LAST PATH I33
J 0
(-5800 3825);
DISPLAY 0.978723 (-5800 3825);
PAINT WHITE (-5800 3825);
DISPLAY INVISIBLE (-5800 3825);
FORCEPROP 1 LAST PART_NUMBER CH622KMEB02
J 0
(-5800 3525);
DISPLAY 0.489362 (-5800 3525);
PAINT SKYBLUE (-5800 3525);
DISPLAY INVISIBLE (-5800 3525);
FORCEADD Q_CAP..1
(-5400 3675);
FORCEPROP 1 LAST LOCATION C2195
J 0
(-5350 3775);
DISPLAY 0.489362 (-5350 3775);
PAINT SKYBLUE (-5350 3775);
FORCEPROP 2 LAST $SEC 1
J 0
(-5350 3875);
DISPLAY 0.680851 (-5350 3875);
PAINT MONO (-5350 3875);
DISPLAY INVISIBLE (-5350 3875);
FORCEPROP 2 LAST CDS_SEC 1
J 0
(-5350 3875);
DISPLAY 1.021277 (-5350 3875);
DISPLAY INVISIBLE (-5350 3875);
FORCEPROP 1 LASTPIN (-5400 3775) $PN 1
J 0
(-5390 3755);
DISPLAY 0.489362 (-5390 3755);
FORCEPROP 1 LASTPIN (-5400 3575) $PN 2
J 0
(-5390 3555);
DISPLAY 0.489362 (-5390 3555);
FORCEPROP 1 LAST MATERIAL X6S
J 0
(-5350 3575);
DISPLAY 0.489362 (-5350 3575);
PAINT SKYBLUE (-5350 3575);
FORCEPROP 1 LAST TOLERANCE 20%
J 0
(-5350 3625);
DISPLAY 0.489362 (-5350 3625);
PAINT SKYBLUE (-5350 3625);
FORCEPROP 1 LAST VALUE 22UF
J 0
(-5350 3725);
DISPLAY 0.489362 (-5350 3725);
PAINT SKYBLUE (-5350 3725);
FORCEPROP 1 LAST VOLTAGE 4V
J 0
(-5350 3675);
DISPLAY 0.489362 (-5350 3675);
PAINT SKYBLUE (-5350 3675);
FORCEPROP 1 LAST PACK_TYPE C0402
J 0
(-5350 3475);
DISPLAY 0.489362 (-5350 3475);
PAINT SKYBLUE (-5350 3475);
FORCEPROP 2 LAST CDS_LIB pure_quanta
J 0
(-5400 3675);
PAINT MONO (-5400 3675);
DISPLAY INVISIBLE (-5400 3675);
FORCEPROP 1 LAST PATH I34
J 0
(-5350 3825);
DISPLAY 0.978723 (-5350 3825);
PAINT WHITE (-5350 3825);
DISPLAY INVISIBLE (-5350 3825);
FORCEPROP 1 LAST PART_NUMBER CH622KMEB02
J 0
(-5350 3525);
DISPLAY 0.489362 (-5350 3525);
PAINT SKYBLUE (-5350 3525);
DISPLAY INVISIBLE (-5350 3525);
FORCEADD UNIVERSAL_GND..1
(-5000 2500);
FORCEPROP 3 LASTPIN (-5000 2550) SIG_NAME GND\g
J 0
(-4990 2560);
DISPLAY 0.659574 (-4990 2560);
PAINT MONO (-4990 2560);
DISPLAY INVISIBLE (-4990 2560);
FORCEPROP 2 LAST CDS_LIB pure_quanta_power
J 0
(-5000 2500);
PAINT MONO (-5000 2500);
DISPLAY INVISIBLE (-5000 2500);
FORCEPROP 1 LAST HDL_POWER GND
J 1
(-4975 2425);
DISPLAY 0.872340 (-4975 2425);
PAINT GREEN (-4975 2425);
DISPLAY INVISIBLE (-4975 2425);
FORCEPROP 1 LAST PATH I35
J 0
(-4925 2500);
DISPLAY 0.872340 (-4925 2500);
PAINT AQUA (-4925 2500);
DISPLAY INVISIBLE (-4925 2500);
FORCEADD Q_CAP..1
(-5000 2875);
FORCEPROP 1 LAST LOCATION C2199
J 0
(-4950 2975);
DISPLAY 0.489362 (-4950 2975);
PAINT SKYBLUE (-4950 2975);
FORCEPROP 2 LAST $SEC 1
J 0
(-4950 3075);
DISPLAY 0.680851 (-4950 3075);
PAINT MONO (-4950 3075);
DISPLAY INVISIBLE (-4950 3075);
FORCEPROP 2 LAST CDS_SEC 1
J 0
(-4950 3075);
DISPLAY 1.021277 (-4950 3075);
DISPLAY INVISIBLE (-4950 3075);
FORCEPROP 1 LASTPIN (-5000 2975) $PN 1
J 0
(-4990 2955);
DISPLAY 0.489362 (-4990 2955);
FORCEPROP 1 LASTPIN (-5000 2775) $PN 2
J 0
(-4990 2755);
DISPLAY 0.489362 (-4990 2755);
FORCEPROP 1 LAST MATERIAL X6S
J 0
(-4950 2775);
DISPLAY 0.489362 (-4950 2775);
PAINT SKYBLUE (-4950 2775);
FORCEPROP 1 LAST TOLERANCE 20%
J 0
(-4950 2825);
DISPLAY 0.489362 (-4950 2825);
PAINT SKYBLUE (-4950 2825);
FORCEPROP 1 LAST VALUE 22UF
J 0
(-4950 2925);
DISPLAY 0.489362 (-4950 2925);
PAINT SKYBLUE (-4950 2925);
FORCEPROP 1 LAST VOLTAGE 4V
J 0
(-4950 2875);
DISPLAY 0.489362 (-4950 2875);
PAINT SKYBLUE (-4950 2875);
FORCEPROP 1 LAST PACK_TYPE C0402
J 0
(-4950 2675);
DISPLAY 0.489362 (-4950 2675);
PAINT SKYBLUE (-4950 2675);
FORCEPROP 2 LAST CDS_LIB pure_quanta
J 0
(-5000 2875);
PAINT MONO (-5000 2875);
DISPLAY INVISIBLE (-5000 2875);
FORCEPROP 1 LAST PATH I36
J 0
(-4950 3025);
DISPLAY 0.978723 (-4950 3025);
PAINT WHITE (-4950 3025);
DISPLAY INVISIBLE (-4950 3025);
FORCEPROP 1 LAST PART_NUMBER CH622KMEB02
J 0
(-4950 2725);
DISPLAY 0.489362 (-4950 2725);
PAINT SKYBLUE (-4950 2725);
DISPLAY INVISIBLE (-4950 2725);
FORCEADD UNIVERSAL_POWER..1
(-4425 2350);
FORCEPROP 3 LASTPIN (-4425 2300) SIG_NAME PVDDCR_CPU1_P0\g
J 0
(-4415 2310);
DISPLAY 0.659574 (-4415 2310);
PAINT MONO (-4415 2310);
DISPLAY INVISIBLE (-4415 2310);
FORCEPROP 1 LAST HDL_POWER PVDDCR_CPU1_P0
J 1
(-4425 2400);
DISPLAY 0.489362 (-4425 2400);
PAINT GREEN (-4425 2400);
FORCEPROP 2 LAST CDS_LIB pure_quanta_power
J 0
(-4425 2350);
DISPLAY INVISIBLE (-4425 2350);
FORCEPROP 1 LAST PATH I37
J 0
(-4375 2375);
DISPLAY 0.872340 (-4375 2375);
PAINT AQUA (-4375 2375);
DISPLAY INVISIBLE (-4375 2375);
FORCEADD Q_CAP..1
(-4425 2875);
FORCEPROP 1 LAST LOCATION C2204
J 0
(-4375 2975);
DISPLAY 0.489362 (-4375 2975);
PAINT SKYBLUE (-4375 2975);
FORCEPROP 2 LAST $SEC 1
J 0
(-4375 3075);
DISPLAY 0.680851 (-4375 3075);
PAINT MONO (-4375 3075);
DISPLAY INVISIBLE (-4375 3075);
FORCEPROP 2 LAST CDS_SEC 1
J 0
(-4375 3075);
DISPLAY 1.021277 (-4375 3075);
DISPLAY INVISIBLE (-4375 3075);
FORCEPROP 1 LASTPIN (-4425 2975) $PN 1
J 0
(-4415 2955);
DISPLAY 0.489362 (-4415 2955);
FORCEPROP 1 LASTPIN (-4425 2775) $PN 2
J 0
(-4415 2755);
DISPLAY 0.489362 (-4415 2755);
FORCEPROP 1 LAST MATERIAL X6S
J 0
(-4375 2775);
DISPLAY 0.489362 (-4375 2775);
PAINT SKYBLUE (-4375 2775);
FORCEPROP 1 LAST TOLERANCE 20%
J 0
(-4375 2825);
DISPLAY 0.489362 (-4375 2825);
PAINT SKYBLUE (-4375 2825);
FORCEPROP 1 LAST VALUE 22UF
J 0
(-4375 2925);
DISPLAY 0.489362 (-4375 2925);
PAINT SKYBLUE (-4375 2925);
FORCEPROP 1 LAST VOLTAGE 4V
J 0
(-4375 2875);
DISPLAY 0.489362 (-4375 2875);
PAINT SKYBLUE (-4375 2875);
FORCEPROP 1 LAST PACK_TYPE C0402
J 0
(-4375 2675);
DISPLAY 0.489362 (-4375 2675);
PAINT SKYBLUE (-4375 2675);
FORCEPROP 2 LAST CDS_LIB pure_quanta
J 0
(-4425 2875);
PAINT MONO (-4425 2875);
DISPLAY INVISIBLE (-4425 2875);
FORCEPROP 1 LAST PATH I38
J 0
(-4375 3025);
DISPLAY 0.978723 (-4375 3025);
PAINT WHITE (-4375 3025);
DISPLAY INVISIBLE (-4375 3025);
FORCEPROP 1 LAST PART_NUMBER CH622KMEB02
J 0
(-4375 2725);
DISPLAY 0.489362 (-4375 2725);
PAINT SKYBLUE (-4375 2725);
DISPLAY INVISIBLE (-4375 2725);
FORCEADD UNIVERSAL_GND..1
(-5000 3300);
FORCEPROP 3 LASTPIN (-5000 3350) SIG_NAME GND\g
J 0
(-4990 3360);
DISPLAY 0.659574 (-4990 3360);
PAINT MONO (-4990 3360);
DISPLAY INVISIBLE (-4990 3360);
FORCEPROP 2 LAST CDS_LIB pure_quanta_power
J 0
(-5000 3300);
PAINT MONO (-5000 3300);
DISPLAY INVISIBLE (-5000 3300);
FORCEPROP 1 LAST HDL_POWER GND
J 1
(-4975 3225);
DISPLAY 0.872340 (-4975 3225);
PAINT GREEN (-4975 3225);
DISPLAY INVISIBLE (-4975 3225);
FORCEPROP 1 LAST PATH I39
J 0
(-4925 3300);
DISPLAY 0.872340 (-4925 3300);
PAINT AQUA (-4925 3300);
DISPLAY INVISIBLE (-4925 3300);
FORCEADD Q_CAP..1
(-9000 2875);
FORCEPROP 1 LAST LOCATION C2166
J 0
(-8950 2975);
DISPLAY 0.489362 (-8950 2975);
PAINT SKYBLUE (-8950 2975);
FORCEPROP 2 LAST $SEC 1
J 0
(-8950 3075);
DISPLAY 0.680851 (-8950 3075);
PAINT MONO (-8950 3075);
DISPLAY INVISIBLE (-8950 3075);
FORCEPROP 2 LAST CDS_SEC 1
J 0
(-8950 3075);
DISPLAY 1.021277 (-8950 3075);
DISPLAY INVISIBLE (-8950 3075);
FORCEPROP 1 LASTPIN (-9000 2975) $PN 1
J 0
(-8990 2955);
DISPLAY 0.489362 (-8990 2955);
FORCEPROP 1 LASTPIN (-9000 2775) $PN 2
J 0
(-8990 2755);
DISPLAY 0.489362 (-8990 2755);
FORCEPROP 1 LAST MATERIAL X6S
J 0
(-8950 2775);
DISPLAY 0.489362 (-8950 2775);
PAINT SKYBLUE (-8950 2775);
FORCEPROP 1 LAST TOLERANCE 20%
J 0
(-8950 2825);
DISPLAY 0.489362 (-8950 2825);
PAINT SKYBLUE (-8950 2825);
FORCEPROP 1 LAST VALUE 22UF
J 0
(-8950 2925);
DISPLAY 0.489362 (-8950 2925);
PAINT SKYBLUE (-8950 2925);
FORCEPROP 1 LAST VOLTAGE 4V
J 0
(-8950 2875);
DISPLAY 0.489362 (-8950 2875);
PAINT SKYBLUE (-8950 2875);
FORCEPROP 1 LAST PACK_TYPE C0402
J 0
(-8950 2675);
DISPLAY 0.489362 (-8950 2675);
PAINT SKYBLUE (-8950 2675);
FORCEPROP 2 LAST CDS_LIB pure_quanta
J 0
(-9000 2875);
PAINT MONO (-9000 2875);
DISPLAY INVISIBLE (-9000 2875);
FORCEPROP 1 LAST PATH I4
J 0
(-8950 3025);
DISPLAY 0.978723 (-8950 3025);
PAINT WHITE (-8950 3025);
DISPLAY INVISIBLE (-8950 3025);
FORCEPROP 1 LAST PART_NUMBER CH622KMEB02
J 0
(-8950 2725);
DISPLAY 0.489362 (-8950 2725);
PAINT SKYBLUE (-8950 2725);
DISPLAY INVISIBLE (-8950 2725);
FORCEADD Q_CAP..1
(-5000 3675);
FORCEPROP 1 LAST LOCATION C2198
J 0
(-4950 3775);
DISPLAY 0.489362 (-4950 3775);
PAINT SKYBLUE (-4950 3775);
FORCEPROP 2 LAST $SEC 1
J 0
(-4950 3875);
DISPLAY 0.680851 (-4950 3875);
PAINT MONO (-4950 3875);
DISPLAY INVISIBLE (-4950 3875);
FORCEPROP 2 LAST CDS_SEC 1
J 0
(-4950 3875);
DISPLAY 1.021277 (-4950 3875);
DISPLAY INVISIBLE (-4950 3875);
FORCEPROP 1 LASTPIN (-5000 3775) $PN 1
J 0
(-4990 3755);
DISPLAY 0.489362 (-4990 3755);
FORCEPROP 1 LASTPIN (-5000 3575) $PN 2
J 0
(-4990 3555);
DISPLAY 0.489362 (-4990 3555);
FORCEPROP 1 LAST MATERIAL X6S
J 0
(-4950 3575);
DISPLAY 0.489362 (-4950 3575);
PAINT SKYBLUE (-4950 3575);
FORCEPROP 1 LAST TOLERANCE 20%
J 0
(-4950 3625);
DISPLAY 0.489362 (-4950 3625);
PAINT SKYBLUE (-4950 3625);
FORCEPROP 1 LAST VALUE 22UF
J 0
(-4950 3725);
DISPLAY 0.489362 (-4950 3725);
PAINT SKYBLUE (-4950 3725);
FORCEPROP 1 LAST VOLTAGE 4V
J 0
(-4950 3675);
DISPLAY 0.489362 (-4950 3675);
PAINT SKYBLUE (-4950 3675);
FORCEPROP 1 LAST PACK_TYPE C0402
J 0
(-4950 3475);
DISPLAY 0.489362 (-4950 3475);
PAINT SKYBLUE (-4950 3475);
FORCEPROP 2 LAST CDS_LIB pure_quanta
J 0
(-5000 3675);
PAINT MONO (-5000 3675);
DISPLAY INVISIBLE (-5000 3675);
FORCEPROP 1 LAST PATH I40
J 0
(-4950 3825);
DISPLAY 0.978723 (-4950 3825);
PAINT WHITE (-4950 3825);
DISPLAY INVISIBLE (-4950 3825);
FORCEPROP 1 LAST PART_NUMBER CH622KMEB02
J 0
(-4950 3525);
DISPLAY 0.489362 (-4950 3525);
PAINT SKYBLUE (-4950 3525);
DISPLAY INVISIBLE (-4950 3525);
FORCEADD UNIVERSAL_GND..1
(-5000 4100);
FORCEPROP 3 LASTPIN (-5000 4150) SIG_NAME GND\g
J 0
(-4990 4160);
DISPLAY 0.659574 (-4990 4160);
PAINT MONO (-4990 4160);
DISPLAY INVISIBLE (-4990 4160);
FORCEPROP 2 LAST CDS_LIB pure_quanta_power
J 0
(-5000 4100);
PAINT MONO (-5000 4100);
DISPLAY INVISIBLE (-5000 4100);
FORCEPROP 1 LAST HDL_POWER GND
J 1
(-4975 4025);
DISPLAY 0.872340 (-4975 4025);
PAINT GREEN (-4975 4025);
DISPLAY INVISIBLE (-4975 4025);
FORCEPROP 1 LAST PATH I41
J 0
(-4925 4100);
DISPLAY 0.872340 (-4925 4100);
PAINT AQUA (-4925 4100);
DISPLAY INVISIBLE (-4925 4100);
FORCEADD UNIVERSAL_POWER..1
(-4425 3150);
FORCEPROP 3 LASTPIN (-4425 3100) SIG_NAME PVDDCR_CPU1_P0\g
J 0
(-4415 3110);
DISPLAY 0.659574 (-4415 3110);
PAINT MONO (-4415 3110);
DISPLAY INVISIBLE (-4415 3110);
FORCEPROP 1 LAST HDL_POWER PVDDCR_CPU1_P0
J 1
(-4425 3200);
DISPLAY 0.489362 (-4425 3200);
PAINT GREEN (-4425 3200);
FORCEPROP 2 LAST CDS_LIB pure_quanta_power
J 0
(-4425 3150);
DISPLAY INVISIBLE (-4425 3150);
FORCEPROP 1 LAST PATH I42
J 0
(-4375 3175);
DISPLAY 0.872340 (-4375 3175);
PAINT AQUA (-4375 3175);
DISPLAY INVISIBLE (-4375 3175);
FORCEADD Q_CAP..1
(-4425 3675);
FORCEPROP 1 LAST LOCATION C2203
J 0
(-4375 3775);
DISPLAY 0.489362 (-4375 3775);
PAINT SKYBLUE (-4375 3775);
FORCEPROP 2 LAST $SEC 1
J 0
(-4375 3875);
DISPLAY 0.680851 (-4375 3875);
PAINT MONO (-4375 3875);
DISPLAY INVISIBLE (-4375 3875);
FORCEPROP 2 LAST CDS_SEC 1
J 0
(-4375 3875);
DISPLAY 1.021277 (-4375 3875);
DISPLAY INVISIBLE (-4375 3875);
FORCEPROP 1 LASTPIN (-4425 3775) $PN 1
J 0
(-4415 3755);
DISPLAY 0.489362 (-4415 3755);
FORCEPROP 1 LASTPIN (-4425 3575) $PN 2
J 0
(-4415 3555);
DISPLAY 0.489362 (-4415 3555);
FORCEPROP 1 LAST MATERIAL X6S
J 0
(-4375 3575);
DISPLAY 0.489362 (-4375 3575);
PAINT SKYBLUE (-4375 3575);
FORCEPROP 1 LAST TOLERANCE 20%
J 0
(-4375 3625);
DISPLAY 0.489362 (-4375 3625);
PAINT SKYBLUE (-4375 3625);
FORCEPROP 1 LAST VALUE 22UF
J 0
(-4375 3725);
DISPLAY 0.489362 (-4375 3725);
PAINT SKYBLUE (-4375 3725);
FORCEPROP 1 LAST VOLTAGE 4V
J 0
(-4375 3675);
DISPLAY 0.489362 (-4375 3675);
PAINT SKYBLUE (-4375 3675);
FORCEPROP 1 LAST PACK_TYPE C0402
J 0
(-4375 3475);
DISPLAY 0.489362 (-4375 3475);
PAINT SKYBLUE (-4375 3475);
FORCEPROP 2 LAST CDS_LIB pure_quanta
J 0
(-4425 3675);
PAINT MONO (-4425 3675);
DISPLAY INVISIBLE (-4425 3675);
FORCEPROP 1 LAST PATH I43
J 0
(-4375 3825);
DISPLAY 0.978723 (-4375 3825);
PAINT WHITE (-4375 3825);
DISPLAY INVISIBLE (-4375 3825);
FORCEPROP 1 LAST PART_NUMBER CH622KMEB02
J 0
(-4375 3525);
DISPLAY 0.489362 (-4375 3525);
PAINT SKYBLUE (-4375 3525);
DISPLAY INVISIBLE (-4375 3525);
FORCEADD UNIVERSAL_POWER..1
(-4425 3950);
FORCEPROP 3 LASTPIN (-4425 3900) SIG_NAME PVDDCR_CPU1_P0\g
J 0
(-4415 3910);
DISPLAY 0.659574 (-4415 3910);
PAINT MONO (-4415 3910);
DISPLAY INVISIBLE (-4415 3910);
FORCEPROP 1 LAST HDL_POWER PVDDCR_CPU1_P0
J 1
(-4425 4000);
DISPLAY 0.489362 (-4425 4000);
PAINT GREEN (-4425 4000);
FORCEPROP 2 LAST CDS_LIB pure_quanta_power
J 0
(-4425 3950);
DISPLAY INVISIBLE (-4425 3950);
FORCEPROP 1 LAST PATH I44
J 0
(-4375 3975);
DISPLAY 0.872340 (-4375 3975);
PAINT AQUA (-4375 3975);
DISPLAY INVISIBLE (-4375 3975);
FORCEADD Q_CAP..1
(-8100 4475);
FORCEPROP 1 LAST LOCATION C1922
J 0
(-8050 4575);
DISPLAY 0.489362 (-8050 4575);
PAINT SKYBLUE (-8050 4575);
FORCEPROP 2 LAST $SEC 1
J 0
(-8050 4675);
DISPLAY 0.680851 (-8050 4675);
PAINT MONO (-8050 4675);
DISPLAY INVISIBLE (-8050 4675);
FORCEPROP 2 LAST CDS_SEC 1
J 0
(-8050 4675);
DISPLAY 1.021277 (-8050 4675);
DISPLAY INVISIBLE (-8050 4675);
FORCEPROP 1 LASTPIN (-8100 4575) $PN 1
J 0
(-8090 4555);
DISPLAY 0.489362 (-8090 4555);
FORCEPROP 1 LASTPIN (-8100 4375) $PN 2
J 0
(-8090 4355);
DISPLAY 0.489362 (-8090 4355);
FORCEPROP 1 LAST MATERIAL X6S
J 0
(-8050 4375);
DISPLAY 0.489362 (-8050 4375);
PAINT SKYBLUE (-8050 4375);
FORCEPROP 1 LAST TOLERANCE 20%
J 0
(-8050 4425);
DISPLAY 0.489362 (-8050 4425);
PAINT SKYBLUE (-8050 4425);
FORCEPROP 1 LAST VALUE 22UF
J 0
(-8050 4525);
DISPLAY 0.489362 (-8050 4525);
PAINT SKYBLUE (-8050 4525);
FORCEPROP 1 LAST VOLTAGE 4V
J 0
(-8050 4475);
DISPLAY 0.489362 (-8050 4475);
PAINT SKYBLUE (-8050 4475);
FORCEPROP 1 LAST PACK_TYPE C0402
J 0
(-8050 4275);
DISPLAY 0.489362 (-8050 4275);
PAINT SKYBLUE (-8050 4275);
FORCEPROP 2 LAST CDS_LIB pure_quanta
J 0
(-8100 4475);
PAINT MONO (-8100 4475);
DISPLAY INVISIBLE (-8100 4475);
FORCEPROP 1 LAST PATH I45
J 0
(-8050 4625);
DISPLAY 0.978723 (-8050 4625);
PAINT WHITE (-8050 4625);
DISPLAY INVISIBLE (-8050 4625);
FORCEPROP 1 LAST PART_NUMBER CH622KMEB02
J 0
(-8050 4325);
DISPLAY 0.489362 (-8050 4325);
PAINT SKYBLUE (-8050 4325);
DISPLAY INVISIBLE (-8050 4325);
FORCEADD Q_CAP..1
(-7650 4475);
FORCEPROP 1 LAST LOCATION C263
J 0
(-7600 4575);
DISPLAY 0.489362 (-7600 4575);
PAINT SKYBLUE (-7600 4575);
FORCEPROP 2 LAST $SEC 1
J 0
(-7600 4675);
DISPLAY 0.680851 (-7600 4675);
PAINT MONO (-7600 4675);
DISPLAY INVISIBLE (-7600 4675);
FORCEPROP 2 LAST CDS_SEC 1
J 0
(-7600 4675);
DISPLAY 1.021277 (-7600 4675);
DISPLAY INVISIBLE (-7600 4675);
FORCEPROP 1 LASTPIN (-7650 4575) $PN 1
J 0
(-7640 4555);
DISPLAY 0.489362 (-7640 4555);
FORCEPROP 1 LASTPIN (-7650 4375) $PN 2
J 0
(-7640 4355);
DISPLAY 0.489362 (-7640 4355);
FORCEPROP 1 LAST MATERIAL X6S
J 0
(-7600 4375);
DISPLAY 0.489362 (-7600 4375);
PAINT SKYBLUE (-7600 4375);
FORCEPROP 1 LAST TOLERANCE 20%
J 0
(-7600 4425);
DISPLAY 0.489362 (-7600 4425);
PAINT SKYBLUE (-7600 4425);
FORCEPROP 1 LAST VALUE 22UF
J 0
(-7600 4525);
DISPLAY 0.489362 (-7600 4525);
PAINT SKYBLUE (-7600 4525);
FORCEPROP 1 LAST VOLTAGE 4V
J 0
(-7600 4475);
DISPLAY 0.489362 (-7600 4475);
PAINT SKYBLUE (-7600 4475);
FORCEPROP 1 LAST PACK_TYPE C0402
J 0
(-7600 4275);
DISPLAY 0.489362 (-7600 4275);
PAINT SKYBLUE (-7600 4275);
FORCEPROP 2 LAST CDS_LIB pure_quanta
J 0
(-7650 4475);
PAINT MONO (-7650 4475);
DISPLAY INVISIBLE (-7650 4475);
FORCEPROP 1 LAST PATH I46
J 0
(-7600 4625);
DISPLAY 0.978723 (-7600 4625);
PAINT WHITE (-7600 4625);
DISPLAY INVISIBLE (-7600 4625);
FORCEPROP 1 LAST PART_NUMBER CH622KMEB02
J 0
(-7600 4325);
DISPLAY 0.489362 (-7600 4325);
PAINT SKYBLUE (-7600 4325);
DISPLAY INVISIBLE (-7600 4325);
FORCEADD Q_CAP..1
(-8100 5250);
FORCEPROP 1 LAST LOCATION C4178
J 0
(-8050 5350);
DISPLAY 0.489362 (-8050 5350);
PAINT SKYBLUE (-8050 5350);
FORCEPROP 2 LAST $SEC 1
J 0
(-8050 5450);
DISPLAY 0.680851 (-8050 5450);
PAINT MONO (-8050 5450);
DISPLAY INVISIBLE (-8050 5450);
FORCEPROP 2 LAST CDS_SEC 1
J 0
(-8050 5450);
DISPLAY 1.021277 (-8050 5450);
DISPLAY INVISIBLE (-8050 5450);
FORCEPROP 1 LASTPIN (-8100 5350) $PN 1
J 0
(-8090 5330);
DISPLAY 0.489362 (-8090 5330);
FORCEPROP 1 LASTPIN (-8100 5150) $PN 2
J 0
(-8090 5130);
DISPLAY 0.489362 (-8090 5130);
FORCEPROP 1 LAST MATERIAL X6S
J 0
(-8050 5150);
DISPLAY 0.489362 (-8050 5150);
PAINT SKYBLUE (-8050 5150);
FORCEPROP 1 LAST TOLERANCE 20%
J 0
(-8050 5200);
DISPLAY 0.489362 (-8050 5200);
PAINT SKYBLUE (-8050 5200);
FORCEPROP 1 LAST VALUE 22UF
J 0
(-8050 5300);
DISPLAY 0.489362 (-8050 5300);
PAINT SKYBLUE (-8050 5300);
FORCEPROP 1 LAST VOLTAGE 4V
J 0
(-8050 5250);
DISPLAY 0.489362 (-8050 5250);
PAINT SKYBLUE (-8050 5250);
FORCEPROP 1 LAST PACK_TYPE C0402
J 0
(-8050 5050);
DISPLAY 0.489362 (-8050 5050);
PAINT SKYBLUE (-8050 5050);
FORCEPROP 2 LAST CDS_LIB pure_quanta
J 0
(-8100 5250);
PAINT MONO (-8100 5250);
DISPLAY INVISIBLE (-8100 5250);
FORCEPROP 1 LAST PATH I47
J 0
(-8050 5400);
DISPLAY 0.978723 (-8050 5400);
PAINT WHITE (-8050 5400);
DISPLAY INVISIBLE (-8050 5400);
FORCEPROP 1 LAST PART_NUMBER CH622KMEB02
J 0
(-8050 5100);
DISPLAY 0.489362 (-8050 5100);
PAINT SKYBLUE (-8050 5100);
DISPLAY INVISIBLE (-8050 5100);
FORCEADD Q_CAP..1
(-7650 5250);
FORCEPROP 1 LAST LOCATION C4179
J 0
(-7600 5350);
DISPLAY 0.489362 (-7600 5350);
PAINT SKYBLUE (-7600 5350);
FORCEPROP 2 LAST $SEC 1
J 0
(-7600 5450);
DISPLAY 0.680851 (-7600 5450);
PAINT MONO (-7600 5450);
DISPLAY INVISIBLE (-7600 5450);
FORCEPROP 2 LAST CDS_SEC 1
J 0
(-7600 5450);
DISPLAY 1.021277 (-7600 5450);
DISPLAY INVISIBLE (-7600 5450);
FORCEPROP 1 LASTPIN (-7650 5350) $PN 1
J 0
(-7640 5330);
DISPLAY 0.489362 (-7640 5330);
FORCEPROP 1 LASTPIN (-7650 5150) $PN 2
J 0
(-7640 5130);
DISPLAY 0.489362 (-7640 5130);
FORCEPROP 1 LAST MATERIAL X6S
J 0
(-7600 5150);
DISPLAY 0.489362 (-7600 5150);
PAINT SKYBLUE (-7600 5150);
FORCEPROP 1 LAST TOLERANCE 20%
J 0
(-7600 5200);
DISPLAY 0.489362 (-7600 5200);
PAINT SKYBLUE (-7600 5200);
FORCEPROP 1 LAST VALUE 22UF
J 0
(-7600 5300);
DISPLAY 0.489362 (-7600 5300);
PAINT SKYBLUE (-7600 5300);
FORCEPROP 1 LAST VOLTAGE 4V
J 0
(-7600 5250);
DISPLAY 0.489362 (-7600 5250);
PAINT SKYBLUE (-7600 5250);
FORCEPROP 1 LAST PACK_TYPE C0402
J 0
(-7600 5050);
DISPLAY 0.489362 (-7600 5050);
PAINT SKYBLUE (-7600 5050);
FORCEPROP 2 LAST CDS_LIB pure_quanta
J 0
(-7650 5250);
PAINT MONO (-7650 5250);
DISPLAY INVISIBLE (-7650 5250);
FORCEPROP 1 LAST PATH I48
J 0
(-7600 5400);
DISPLAY 0.978723 (-7600 5400);
PAINT WHITE (-7600 5400);
DISPLAY INVISIBLE (-7600 5400);
FORCEPROP 1 LAST PART_NUMBER CH622KMEB02
J 0
(-7600 5100);
DISPLAY 0.489362 (-7600 5100);
PAINT SKYBLUE (-7600 5100);
DISPLAY INVISIBLE (-7600 5100);
FORCEADD Q_CAP..1
(-7200 4475);
FORCEPROP 1 LAST LOCATION C268
J 0
(-7150 4575);
DISPLAY 0.489362 (-7150 4575);
PAINT SKYBLUE (-7150 4575);
FORCEPROP 2 LAST $SEC 1
J 0
(-7150 4675);
DISPLAY 0.680851 (-7150 4675);
PAINT MONO (-7150 4675);
DISPLAY INVISIBLE (-7150 4675);
FORCEPROP 2 LAST CDS_SEC 1
J 0
(-7150 4675);
DISPLAY 1.021277 (-7150 4675);
DISPLAY INVISIBLE (-7150 4675);
FORCEPROP 1 LASTPIN (-7200 4575) $PN 1
J 0
(-7190 4555);
DISPLAY 0.489362 (-7190 4555);
FORCEPROP 1 LASTPIN (-7200 4375) $PN 2
J 0
(-7190 4355);
DISPLAY 0.489362 (-7190 4355);
FORCEPROP 1 LAST MATERIAL X6S
J 0
(-7150 4375);
DISPLAY 0.489362 (-7150 4375);
PAINT SKYBLUE (-7150 4375);
FORCEPROP 1 LAST TOLERANCE 20%
J 0
(-7150 4425);
DISPLAY 0.489362 (-7150 4425);
PAINT SKYBLUE (-7150 4425);
FORCEPROP 1 LAST VALUE 22UF
J 0
(-7150 4525);
DISPLAY 0.489362 (-7150 4525);
PAINT SKYBLUE (-7150 4525);
FORCEPROP 1 LAST VOLTAGE 4V
J 0
(-7150 4475);
DISPLAY 0.489362 (-7150 4475);
PAINT SKYBLUE (-7150 4475);
FORCEPROP 1 LAST PACK_TYPE C0402
J 0
(-7150 4275);
DISPLAY 0.489362 (-7150 4275);
PAINT SKYBLUE (-7150 4275);
FORCEPROP 2 LAST CDS_LIB pure_quanta
J 0
(-7200 4475);
PAINT MONO (-7200 4475);
DISPLAY INVISIBLE (-7200 4475);
FORCEPROP 1 LAST PATH I49
J 0
(-7150 4625);
DISPLAY 0.978723 (-7150 4625);
PAINT WHITE (-7150 4625);
DISPLAY INVISIBLE (-7150 4625);
FORCEPROP 1 LAST PART_NUMBER CH622KMEB02
J 0
(-7150 4325);
DISPLAY 0.489362 (-7150 4325);
PAINT SKYBLUE (-7150 4325);
DISPLAY INVISIBLE (-7150 4325);
FORCEADD Q_CAP..1
(-8550 2875);
FORCEPROP 1 LAST LOCATION C2170
J 0
(-8500 2975);
DISPLAY 0.489362 (-8500 2975);
PAINT SKYBLUE (-8500 2975);
FORCEPROP 2 LAST $SEC 1
J 0
(-8500 3075);
DISPLAY 0.680851 (-8500 3075);
PAINT MONO (-8500 3075);
DISPLAY INVISIBLE (-8500 3075);
FORCEPROP 2 LAST CDS_SEC 1
J 0
(-8500 3075);
DISPLAY 1.021277 (-8500 3075);
DISPLAY INVISIBLE (-8500 3075);
FORCEPROP 1 LASTPIN (-8550 2975) $PN 1
J 0
(-8540 2955);
DISPLAY 0.489362 (-8540 2955);
FORCEPROP 1 LASTPIN (-8550 2775) $PN 2
J 0
(-8540 2755);
DISPLAY 0.489362 (-8540 2755);
FORCEPROP 1 LAST MATERIAL X6S
J 0
(-8500 2775);
DISPLAY 0.489362 (-8500 2775);
PAINT SKYBLUE (-8500 2775);
FORCEPROP 1 LAST TOLERANCE 20%
J 0
(-8500 2825);
DISPLAY 0.489362 (-8500 2825);
PAINT SKYBLUE (-8500 2825);
FORCEPROP 1 LAST VALUE 22UF
J 0
(-8500 2925);
DISPLAY 0.489362 (-8500 2925);
PAINT SKYBLUE (-8500 2925);
FORCEPROP 1 LAST VOLTAGE 4V
J 0
(-8500 2875);
DISPLAY 0.489362 (-8500 2875);
PAINT SKYBLUE (-8500 2875);
FORCEPROP 1 LAST PACK_TYPE C0402
J 0
(-8500 2675);
DISPLAY 0.489362 (-8500 2675);
PAINT SKYBLUE (-8500 2675);
FORCEPROP 2 LAST CDS_LIB pure_quanta
J 0
(-8550 2875);
PAINT MONO (-8550 2875);
DISPLAY INVISIBLE (-8550 2875);
FORCEPROP 1 LAST PATH I5
J 0
(-8500 3025);
DISPLAY 0.978723 (-8500 3025);
PAINT WHITE (-8500 3025);
DISPLAY INVISIBLE (-8500 3025);
FORCEPROP 1 LAST PART_NUMBER CH622KMEB02
J 0
(-8500 2725);
DISPLAY 0.489362 (-8500 2725);
PAINT SKYBLUE (-8500 2725);
DISPLAY INVISIBLE (-8500 2725);
FORCEADD Q_CAP..1
(-7200 5250);
FORCEPROP 1 LAST LOCATION C267
J 0
(-7150 5350);
DISPLAY 0.489362 (-7150 5350);
PAINT SKYBLUE (-7150 5350);
FORCEPROP 2 LAST $SEC 1
J 0
(-7150 5450);
DISPLAY 0.680851 (-7150 5450);
PAINT MONO (-7150 5450);
DISPLAY INVISIBLE (-7150 5450);
FORCEPROP 2 LAST CDS_SEC 1
J 0
(-7150 5450);
DISPLAY 1.021277 (-7150 5450);
DISPLAY INVISIBLE (-7150 5450);
FORCEPROP 1 LASTPIN (-7200 5350) $PN 1
J 0
(-7190 5330);
DISPLAY 0.489362 (-7190 5330);
FORCEPROP 1 LASTPIN (-7200 5150) $PN 2
J 0
(-7190 5130);
DISPLAY 0.489362 (-7190 5130);
FORCEPROP 1 LAST MATERIAL X6S
J 0
(-7150 5150);
DISPLAY 0.489362 (-7150 5150);
PAINT SKYBLUE (-7150 5150);
FORCEPROP 1 LAST TOLERANCE 20%
J 0
(-7150 5200);
DISPLAY 0.489362 (-7150 5200);
PAINT SKYBLUE (-7150 5200);
FORCEPROP 1 LAST VALUE 22UF
J 0
(-7150 5300);
DISPLAY 0.489362 (-7150 5300);
PAINT SKYBLUE (-7150 5300);
FORCEPROP 1 LAST VOLTAGE 4V
J 0
(-7150 5250);
DISPLAY 0.489362 (-7150 5250);
PAINT SKYBLUE (-7150 5250);
FORCEPROP 1 LAST PACK_TYPE C0402
J 0
(-7150 5050);
DISPLAY 0.489362 (-7150 5050);
PAINT SKYBLUE (-7150 5050);
FORCEPROP 2 LAST CDS_LIB pure_quanta
J 0
(-7200 5250);
PAINT MONO (-7200 5250);
DISPLAY INVISIBLE (-7200 5250);
FORCEPROP 1 LAST PATH I50
J 0
(-7150 5400);
DISPLAY 0.978723 (-7150 5400);
PAINT WHITE (-7150 5400);
DISPLAY INVISIBLE (-7150 5400);
FORCEPROP 1 LAST PART_NUMBER CH622KMEB02
J 0
(-7150 5100);
DISPLAY 0.489362 (-7150 5100);
PAINT SKYBLUE (-7150 5100);
DISPLAY INVISIBLE (-7150 5100);
FORCEADD Q_CAP..1
(-6750 4475);
FORCEPROP 1 LAST LOCATION C271
J 0
(-6700 4575);
DISPLAY 0.489362 (-6700 4575);
PAINT SKYBLUE (-6700 4575);
FORCEPROP 2 LAST $SEC 1
J 0
(-6700 4675);
DISPLAY 0.680851 (-6700 4675);
PAINT MONO (-6700 4675);
DISPLAY INVISIBLE (-6700 4675);
FORCEPROP 2 LAST CDS_SEC 1
J 0
(-6700 4675);
DISPLAY 1.021277 (-6700 4675);
DISPLAY INVISIBLE (-6700 4675);
FORCEPROP 1 LASTPIN (-6750 4575) $PN 1
J 0
(-6740 4555);
DISPLAY 0.489362 (-6740 4555);
FORCEPROP 1 LASTPIN (-6750 4375) $PN 2
J 0
(-6740 4355);
DISPLAY 0.489362 (-6740 4355);
FORCEPROP 1 LAST MATERIAL X6S
J 0
(-6700 4375);
DISPLAY 0.489362 (-6700 4375);
PAINT SKYBLUE (-6700 4375);
FORCEPROP 1 LAST TOLERANCE 20%
J 0
(-6700 4425);
DISPLAY 0.489362 (-6700 4425);
PAINT SKYBLUE (-6700 4425);
FORCEPROP 1 LAST VALUE 22UF
J 0
(-6700 4525);
DISPLAY 0.489362 (-6700 4525);
PAINT SKYBLUE (-6700 4525);
FORCEPROP 1 LAST VOLTAGE 4V
J 0
(-6700 4475);
DISPLAY 0.489362 (-6700 4475);
PAINT SKYBLUE (-6700 4475);
FORCEPROP 1 LAST PACK_TYPE C0402
J 0
(-6700 4275);
DISPLAY 0.489362 (-6700 4275);
PAINT SKYBLUE (-6700 4275);
FORCEPROP 2 LAST CDS_LIB pure_quanta
J 0
(-6750 4475);
PAINT MONO (-6750 4475);
DISPLAY INVISIBLE (-6750 4475);
FORCEPROP 1 LAST PATH I51
J 0
(-6700 4625);
DISPLAY 0.978723 (-6700 4625);
PAINT WHITE (-6700 4625);
DISPLAY INVISIBLE (-6700 4625);
FORCEPROP 1 LAST PART_NUMBER CH622KMEB02
J 0
(-6700 4325);
DISPLAY 0.489362 (-6700 4325);
PAINT SKYBLUE (-6700 4325);
DISPLAY INVISIBLE (-6700 4325);
FORCEADD Q_CAP..1
(-6300 4475);
FORCEPROP 1 LAST LOCATION C273
J 0
(-6250 4575);
DISPLAY 0.489362 (-6250 4575);
PAINT SKYBLUE (-6250 4575);
FORCEPROP 2 LAST $SEC 1
J 0
(-6250 4675);
DISPLAY 0.680851 (-6250 4675);
PAINT MONO (-6250 4675);
DISPLAY INVISIBLE (-6250 4675);
FORCEPROP 2 LAST CDS_SEC 1
J 0
(-6250 4675);
DISPLAY 1.021277 (-6250 4675);
DISPLAY INVISIBLE (-6250 4675);
FORCEPROP 1 LASTPIN (-6300 4575) $PN 1
J 0
(-6290 4555);
DISPLAY 0.489362 (-6290 4555);
FORCEPROP 1 LASTPIN (-6300 4375) $PN 2
J 0
(-6290 4355);
DISPLAY 0.489362 (-6290 4355);
FORCEPROP 1 LAST MATERIAL X6S
J 0
(-6250 4375);
DISPLAY 0.489362 (-6250 4375);
PAINT SKYBLUE (-6250 4375);
FORCEPROP 1 LAST TOLERANCE 20%
J 0
(-6250 4425);
DISPLAY 0.489362 (-6250 4425);
PAINT SKYBLUE (-6250 4425);
FORCEPROP 1 LAST VALUE 22UF
J 0
(-6250 4525);
DISPLAY 0.489362 (-6250 4525);
PAINT SKYBLUE (-6250 4525);
FORCEPROP 1 LAST VOLTAGE 4V
J 0
(-6250 4475);
DISPLAY 0.489362 (-6250 4475);
PAINT SKYBLUE (-6250 4475);
FORCEPROP 1 LAST PACK_TYPE C0402
J 0
(-6250 4275);
DISPLAY 0.489362 (-6250 4275);
PAINT SKYBLUE (-6250 4275);
FORCEPROP 2 LAST CDS_LIB pure_quanta
J 0
(-6300 4475);
PAINT MONO (-6300 4475);
DISPLAY INVISIBLE (-6300 4475);
FORCEPROP 1 LAST PATH I52
J 0
(-6250 4625);
DISPLAY 0.978723 (-6250 4625);
PAINT WHITE (-6250 4625);
DISPLAY INVISIBLE (-6250 4625);
FORCEPROP 1 LAST PART_NUMBER CH622KMEB02
J 0
(-6250 4325);
DISPLAY 0.489362 (-6250 4325);
PAINT SKYBLUE (-6250 4325);
DISPLAY INVISIBLE (-6250 4325);
FORCEADD Q_CAP..1
(-6750 5250);
FORCEPROP 1 LAST LOCATION C270
J 0
(-6700 5350);
DISPLAY 0.489362 (-6700 5350);
PAINT SKYBLUE (-6700 5350);
FORCEPROP 2 LAST $SEC 1
J 0
(-6700 5450);
DISPLAY 0.680851 (-6700 5450);
PAINT MONO (-6700 5450);
DISPLAY INVISIBLE (-6700 5450);
FORCEPROP 2 LAST CDS_SEC 1
J 0
(-6700 5450);
DISPLAY 1.021277 (-6700 5450);
DISPLAY INVISIBLE (-6700 5450);
FORCEPROP 1 LASTPIN (-6750 5350) $PN 1
J 0
(-6740 5330);
DISPLAY 0.489362 (-6740 5330);
FORCEPROP 1 LASTPIN (-6750 5150) $PN 2
J 0
(-6740 5130);
DISPLAY 0.489362 (-6740 5130);
FORCEPROP 1 LAST MATERIAL X6S
J 0
(-6700 5150);
DISPLAY 0.489362 (-6700 5150);
PAINT SKYBLUE (-6700 5150);
FORCEPROP 1 LAST TOLERANCE 20%
J 0
(-6700 5200);
DISPLAY 0.489362 (-6700 5200);
PAINT SKYBLUE (-6700 5200);
FORCEPROP 1 LAST VALUE 22UF
J 0
(-6700 5300);
DISPLAY 0.489362 (-6700 5300);
PAINT SKYBLUE (-6700 5300);
FORCEPROP 1 LAST VOLTAGE 4V
J 0
(-6700 5250);
DISPLAY 0.489362 (-6700 5250);
PAINT SKYBLUE (-6700 5250);
FORCEPROP 1 LAST PACK_TYPE C0402
J 0
(-6700 5050);
DISPLAY 0.489362 (-6700 5050);
PAINT SKYBLUE (-6700 5050);
FORCEPROP 2 LAST CDS_LIB pure_quanta
J 0
(-6750 5250);
PAINT MONO (-6750 5250);
DISPLAY INVISIBLE (-6750 5250);
FORCEPROP 1 LAST PATH I53
J 0
(-6700 5400);
DISPLAY 0.978723 (-6700 5400);
PAINT WHITE (-6700 5400);
DISPLAY INVISIBLE (-6700 5400);
FORCEPROP 1 LAST PART_NUMBER CH622KMEB02
J 0
(-6700 5100);
DISPLAY 0.489362 (-6700 5100);
PAINT SKYBLUE (-6700 5100);
DISPLAY INVISIBLE (-6700 5100);
FORCEADD Q_CAP..1
(-5850 4475);
FORCEPROP 1 LAST LOCATION C275
J 0
(-5800 4575);
DISPLAY 0.489362 (-5800 4575);
PAINT SKYBLUE (-5800 4575);
FORCEPROP 2 LAST $SEC 1
J 0
(-5800 4675);
DISPLAY 0.680851 (-5800 4675);
PAINT MONO (-5800 4675);
DISPLAY INVISIBLE (-5800 4675);
FORCEPROP 2 LAST CDS_SEC 1
J 0
(-5800 4675);
DISPLAY 1.021277 (-5800 4675);
DISPLAY INVISIBLE (-5800 4675);
FORCEPROP 1 LASTPIN (-5850 4575) $PN 1
J 0
(-5840 4555);
DISPLAY 0.489362 (-5840 4555);
FORCEPROP 1 LASTPIN (-5850 4375) $PN 2
J 0
(-5840 4355);
DISPLAY 0.489362 (-5840 4355);
FORCEPROP 1 LAST MATERIAL X6S
J 0
(-5800 4375);
DISPLAY 0.489362 (-5800 4375);
PAINT SKYBLUE (-5800 4375);
FORCEPROP 1 LAST TOLERANCE 20%
J 0
(-5800 4425);
DISPLAY 0.489362 (-5800 4425);
PAINT SKYBLUE (-5800 4425);
FORCEPROP 1 LAST VALUE 22UF
J 0
(-5800 4525);
DISPLAY 0.489362 (-5800 4525);
PAINT SKYBLUE (-5800 4525);
FORCEPROP 1 LAST VOLTAGE 4V
J 0
(-5800 4475);
DISPLAY 0.489362 (-5800 4475);
PAINT SKYBLUE (-5800 4475);
FORCEPROP 1 LAST PACK_TYPE C0402
J 0
(-5800 4275);
DISPLAY 0.489362 (-5800 4275);
PAINT SKYBLUE (-5800 4275);
FORCEPROP 2 LAST CDS_LIB pure_quanta
J 0
(-5850 4475);
PAINT MONO (-5850 4475);
DISPLAY INVISIBLE (-5850 4475);
FORCEPROP 1 LAST PATH I54
J 0
(-5800 4625);
DISPLAY 0.978723 (-5800 4625);
PAINT WHITE (-5800 4625);
DISPLAY INVISIBLE (-5800 4625);
FORCEPROP 1 LAST PART_NUMBER CH622KMEB02
J 0
(-5800 4325);
DISPLAY 0.489362 (-5800 4325);
PAINT SKYBLUE (-5800 4325);
DISPLAY INVISIBLE (-5800 4325);
FORCEADD Q_CAP..1
(-5400 4475);
FORCEPROP 1 LAST LOCATION C277
J 0
(-5350 4575);
DISPLAY 0.489362 (-5350 4575);
PAINT SKYBLUE (-5350 4575);
FORCEPROP 2 LAST $SEC 1
J 0
(-5350 4675);
DISPLAY 0.680851 (-5350 4675);
PAINT MONO (-5350 4675);
DISPLAY INVISIBLE (-5350 4675);
FORCEPROP 2 LAST CDS_SEC 1
J 0
(-5350 4675);
DISPLAY 1.021277 (-5350 4675);
DISPLAY INVISIBLE (-5350 4675);
FORCEPROP 1 LASTPIN (-5400 4575) $PN 1
J 0
(-5390 4555);
DISPLAY 0.489362 (-5390 4555);
FORCEPROP 1 LASTPIN (-5400 4375) $PN 2
J 0
(-5390 4355);
DISPLAY 0.489362 (-5390 4355);
FORCEPROP 1 LAST MATERIAL X6S
J 0
(-5350 4375);
DISPLAY 0.489362 (-5350 4375);
PAINT SKYBLUE (-5350 4375);
FORCEPROP 1 LAST TOLERANCE 20%
J 0
(-5350 4425);
DISPLAY 0.489362 (-5350 4425);
PAINT SKYBLUE (-5350 4425);
FORCEPROP 1 LAST VALUE 22UF
J 0
(-5350 4525);
DISPLAY 0.489362 (-5350 4525);
PAINT SKYBLUE (-5350 4525);
FORCEPROP 1 LAST VOLTAGE 4V
J 0
(-5350 4475);
DISPLAY 0.489362 (-5350 4475);
PAINT SKYBLUE (-5350 4475);
FORCEPROP 1 LAST PACK_TYPE C0402
J 0
(-5350 4275);
DISPLAY 0.489362 (-5350 4275);
PAINT SKYBLUE (-5350 4275);
FORCEPROP 2 LAST CDS_LIB pure_quanta
J 0
(-5400 4475);
PAINT MONO (-5400 4475);
DISPLAY INVISIBLE (-5400 4475);
FORCEPROP 1 LAST PATH I55
J 0
(-5350 4625);
DISPLAY 0.978723 (-5350 4625);
PAINT WHITE (-5350 4625);
DISPLAY INVISIBLE (-5350 4625);
FORCEPROP 1 LAST PART_NUMBER CH622KMEB02
J 0
(-5350 4325);
DISPLAY 0.489362 (-5350 4325);
PAINT SKYBLUE (-5350 4325);
DISPLAY INVISIBLE (-5350 4325);
FORCEADD Q_CAP..1
(-5850 5250);
FORCEPROP 1 LAST LOCATION C274
J 0
(-5800 5350);
DISPLAY 0.489362 (-5800 5350);
PAINT SKYBLUE (-5800 5350);
FORCEPROP 2 LAST $SEC 1
J 0
(-5800 5450);
DISPLAY 0.680851 (-5800 5450);
PAINT MONO (-5800 5450);
DISPLAY INVISIBLE (-5800 5450);
FORCEPROP 2 LAST CDS_SEC 1
J 0
(-5800 5450);
DISPLAY 1.021277 (-5800 5450);
DISPLAY INVISIBLE (-5800 5450);
FORCEPROP 1 LASTPIN (-5850 5350) $PN 1
J 0
(-5840 5330);
DISPLAY 0.489362 (-5840 5330);
FORCEPROP 1 LASTPIN (-5850 5150) $PN 2
J 0
(-5840 5130);
DISPLAY 0.489362 (-5840 5130);
FORCEPROP 1 LAST MATERIAL X6S
J 0
(-5800 5150);
DISPLAY 0.489362 (-5800 5150);
PAINT SKYBLUE (-5800 5150);
FORCEPROP 1 LAST TOLERANCE 20%
J 0
(-5800 5200);
DISPLAY 0.489362 (-5800 5200);
PAINT SKYBLUE (-5800 5200);
FORCEPROP 1 LAST VALUE 22UF
J 0
(-5800 5300);
DISPLAY 0.489362 (-5800 5300);
PAINT SKYBLUE (-5800 5300);
FORCEPROP 1 LAST VOLTAGE 4V
J 0
(-5800 5250);
DISPLAY 0.489362 (-5800 5250);
PAINT SKYBLUE (-5800 5250);
FORCEPROP 1 LAST PACK_TYPE C0402
J 0
(-5800 5050);
DISPLAY 0.489362 (-5800 5050);
PAINT SKYBLUE (-5800 5050);
FORCEPROP 2 LAST CDS_LIB pure_quanta
J 0
(-5850 5250);
PAINT MONO (-5850 5250);
DISPLAY INVISIBLE (-5850 5250);
FORCEPROP 1 LAST PATH I56
J 0
(-5800 5400);
DISPLAY 0.978723 (-5800 5400);
PAINT WHITE (-5800 5400);
DISPLAY INVISIBLE (-5800 5400);
FORCEPROP 1 LAST PART_NUMBER CH622KMEB02
J 0
(-5800 5100);
DISPLAY 0.489362 (-5800 5100);
PAINT SKYBLUE (-5800 5100);
DISPLAY INVISIBLE (-5800 5100);
FORCEADD Q_CAP..1
(-5400 5250);
FORCEPROP 1 LAST LOCATION C276
J 0
(-5350 5350);
DISPLAY 0.489362 (-5350 5350);
PAINT SKYBLUE (-5350 5350);
FORCEPROP 2 LAST $SEC 1
J 0
(-5350 5450);
DISPLAY 0.680851 (-5350 5450);
PAINT MONO (-5350 5450);
DISPLAY INVISIBLE (-5350 5450);
FORCEPROP 2 LAST CDS_SEC 1
J 0
(-5350 5450);
DISPLAY 1.021277 (-5350 5450);
DISPLAY INVISIBLE (-5350 5450);
FORCEPROP 1 LASTPIN (-5400 5350) $PN 1
J 0
(-5390 5330);
DISPLAY 0.489362 (-5390 5330);
FORCEPROP 1 LASTPIN (-5400 5150) $PN 2
J 0
(-5390 5130);
DISPLAY 0.489362 (-5390 5130);
FORCEPROP 1 LAST MATERIAL X6S
J 0
(-5350 5150);
DISPLAY 0.489362 (-5350 5150);
PAINT SKYBLUE (-5350 5150);
FORCEPROP 1 LAST TOLERANCE 20%
J 0
(-5350 5200);
DISPLAY 0.489362 (-5350 5200);
PAINT SKYBLUE (-5350 5200);
FORCEPROP 1 LAST VALUE 22UF
J 0
(-5350 5300);
DISPLAY 0.489362 (-5350 5300);
PAINT SKYBLUE (-5350 5300);
FORCEPROP 1 LAST VOLTAGE 4V
J 0
(-5350 5250);
DISPLAY 0.489362 (-5350 5250);
PAINT SKYBLUE (-5350 5250);
FORCEPROP 1 LAST PACK_TYPE C0402
J 0
(-5350 5050);
DISPLAY 0.489362 (-5350 5050);
PAINT SKYBLUE (-5350 5050);
FORCEPROP 2 LAST CDS_LIB pure_quanta
J 0
(-5400 5250);
PAINT MONO (-5400 5250);
DISPLAY INVISIBLE (-5400 5250);
FORCEPROP 1 LAST PATH I57
J 0
(-5350 5400);
DISPLAY 0.978723 (-5350 5400);
PAINT WHITE (-5350 5400);
DISPLAY INVISIBLE (-5350 5400);
FORCEPROP 1 LAST PART_NUMBER CH622KMEB02
J 0
(-5350 5100);
DISPLAY 0.489362 (-5350 5100);
PAINT SKYBLUE (-5350 5100);
DISPLAY INVISIBLE (-5350 5100);
FORCEADD Q_CAP..1
(-5000 4475);
FORCEPROP 1 LAST LOCATION C279
J 0
(-4950 4575);
DISPLAY 0.489362 (-4950 4575);
PAINT SKYBLUE (-4950 4575);
FORCEPROP 2 LAST $SEC 1
J 0
(-4950 4675);
DISPLAY 0.680851 (-4950 4675);
PAINT MONO (-4950 4675);
DISPLAY INVISIBLE (-4950 4675);
FORCEPROP 2 LAST CDS_SEC 1
J 0
(-4950 4675);
DISPLAY 1.021277 (-4950 4675);
DISPLAY INVISIBLE (-4950 4675);
FORCEPROP 1 LASTPIN (-5000 4575) $PN 1
J 0
(-4990 4555);
DISPLAY 0.489362 (-4990 4555);
FORCEPROP 1 LASTPIN (-5000 4375) $PN 2
J 0
(-4990 4355);
DISPLAY 0.489362 (-4990 4355);
FORCEPROP 1 LAST MATERIAL X6S
J 0
(-4950 4375);
DISPLAY 0.489362 (-4950 4375);
PAINT SKYBLUE (-4950 4375);
FORCEPROP 1 LAST TOLERANCE 20%
J 0
(-4950 4425);
DISPLAY 0.489362 (-4950 4425);
PAINT SKYBLUE (-4950 4425);
FORCEPROP 1 LAST VALUE 22UF
J 0
(-4950 4525);
DISPLAY 0.489362 (-4950 4525);
PAINT SKYBLUE (-4950 4525);
FORCEPROP 1 LAST VOLTAGE 4V
J 0
(-4950 4475);
DISPLAY 0.489362 (-4950 4475);
PAINT SKYBLUE (-4950 4475);
FORCEPROP 1 LAST PACK_TYPE C0402
J 0
(-4950 4275);
DISPLAY 0.489362 (-4950 4275);
PAINT SKYBLUE (-4950 4275);
FORCEPROP 2 LAST CDS_LIB pure_quanta
J 0
(-5000 4475);
PAINT MONO (-5000 4475);
DISPLAY INVISIBLE (-5000 4475);
FORCEPROP 1 LAST PATH I58
J 0
(-4950 4625);
DISPLAY 0.978723 (-4950 4625);
PAINT WHITE (-4950 4625);
DISPLAY INVISIBLE (-4950 4625);
FORCEPROP 1 LAST PART_NUMBER CH622KMEB02
J 0
(-4950 4325);
DISPLAY 0.489362 (-4950 4325);
PAINT SKYBLUE (-4950 4325);
DISPLAY INVISIBLE (-4950 4325);
FORCEADD UNIVERSAL_GND..1
(-5000 4875);
FORCEPROP 3 LASTPIN (-5000 4925) SIG_NAME GND\g
J 0
(-4990 4935);
DISPLAY 0.659574 (-4990 4935);
PAINT MONO (-4990 4935);
DISPLAY INVISIBLE (-4990 4935);
FORCEPROP 2 LAST CDS_LIB pure_quanta_power
J 0
(-5000 4875);
PAINT MONO (-5000 4875);
DISPLAY INVISIBLE (-5000 4875);
FORCEPROP 1 LAST HDL_POWER GND
J 1
(-4975 4800);
DISPLAY 0.872340 (-4975 4800);
PAINT GREEN (-4975 4800);
DISPLAY INVISIBLE (-4975 4800);
FORCEPROP 1 LAST PATH I59
J 0
(-4925 4875);
DISPLAY 0.872340 (-4925 4875);
PAINT AQUA (-4925 4875);
DISPLAY INVISIBLE (-4925 4875);
FORCEADD UNIVERSAL_POWER..1
(-9000 3150);
FORCEPROP 3 LASTPIN (-9000 3100) SIG_NAME PVDDCR_CPU0_P0\g
J 0
(-8990 3110);
DISPLAY 0.659574 (-8990 3110);
PAINT MONO (-8990 3110);
DISPLAY INVISIBLE (-8990 3110);
FORCEPROP 1 LAST HDL_POWER PVDDCR_CPU0_P0
J 1
(-9000 3200);
DISPLAY 0.489362 (-9000 3200);
PAINT GREEN (-9000 3200);
FORCEPROP 2 LAST CDS_LIB pure_quanta_power
J 0
(-9000 3150);
DISPLAY INVISIBLE (-9000 3150);
FORCEPROP 1 LAST PATH I6
J 0
(-8950 3175);
DISPLAY 0.872340 (-8950 3175);
PAINT AQUA (-8950 3175);
DISPLAY INVISIBLE (-8950 3175);
FORCEADD Q_CAP..1
(-4425 4475);
FORCEPROP 1 LAST LOCATION C2202
J 0
(-4375 4575);
DISPLAY 0.489362 (-4375 4575);
PAINT SKYBLUE (-4375 4575);
FORCEPROP 2 LAST $SEC 1
J 0
(-4375 4675);
DISPLAY 0.680851 (-4375 4675);
PAINT MONO (-4375 4675);
DISPLAY INVISIBLE (-4375 4675);
FORCEPROP 2 LAST CDS_SEC 1
J 0
(-4375 4675);
DISPLAY 1.021277 (-4375 4675);
DISPLAY INVISIBLE (-4375 4675);
FORCEPROP 1 LASTPIN (-4425 4575) $PN 1
J 0
(-4415 4555);
DISPLAY 0.489362 (-4415 4555);
FORCEPROP 1 LASTPIN (-4425 4375) $PN 2
J 0
(-4415 4355);
DISPLAY 0.489362 (-4415 4355);
FORCEPROP 1 LAST MATERIAL X6S
J 0
(-4375 4375);
DISPLAY 0.489362 (-4375 4375);
PAINT SKYBLUE (-4375 4375);
FORCEPROP 1 LAST TOLERANCE 20%
J 0
(-4375 4425);
DISPLAY 0.489362 (-4375 4425);
PAINT SKYBLUE (-4375 4425);
FORCEPROP 1 LAST VALUE 22UF
J 0
(-4375 4525);
DISPLAY 0.489362 (-4375 4525);
PAINT SKYBLUE (-4375 4525);
FORCEPROP 1 LAST VOLTAGE 4V
J 0
(-4375 4475);
DISPLAY 0.489362 (-4375 4475);
PAINT SKYBLUE (-4375 4475);
FORCEPROP 1 LAST PACK_TYPE C0402
J 0
(-4375 4275);
DISPLAY 0.489362 (-4375 4275);
PAINT SKYBLUE (-4375 4275);
FORCEPROP 2 LAST CDS_LIB pure_quanta
J 0
(-4425 4475);
PAINT MONO (-4425 4475);
DISPLAY INVISIBLE (-4425 4475);
FORCEPROP 1 LAST PATH I60
J 0
(-4375 4625);
DISPLAY 0.978723 (-4375 4625);
PAINT WHITE (-4375 4625);
DISPLAY INVISIBLE (-4375 4625);
FORCEPROP 1 LAST PART_NUMBER CH622KMEB02
J 0
(-4375 4325);
DISPLAY 0.489362 (-4375 4325);
PAINT SKYBLUE (-4375 4325);
DISPLAY INVISIBLE (-4375 4325);
FORCEADD UNIVERSAL_POWER..1
(-4425 4750);
FORCEPROP 3 LASTPIN (-4425 4700) SIG_NAME PVDDCR_CPU1_P0\g
J 0
(-4415 4710);
DISPLAY 0.659574 (-4415 4710);
PAINT MONO (-4415 4710);
DISPLAY INVISIBLE (-4415 4710);
FORCEPROP 1 LAST HDL_POWER PVDDCR_CPU1_P0
J 1
(-4425 4800);
DISPLAY 0.489362 (-4425 4800);
PAINT GREEN (-4425 4800);
FORCEPROP 2 LAST CDS_LIB pure_quanta_power
J 0
(-4425 4750);
DISPLAY INVISIBLE (-4425 4750);
FORCEPROP 1 LAST PATH I61
J 0
(-4375 4775);
DISPLAY 0.872340 (-4375 4775);
PAINT AQUA (-4375 4775);
DISPLAY INVISIBLE (-4375 4775);
FORCEADD Q_CAP..1
(-5000 5250);
FORCEPROP 1 LAST LOCATION C278
J 0
(-4950 5350);
DISPLAY 0.489362 (-4950 5350);
PAINT SKYBLUE (-4950 5350);
FORCEPROP 2 LAST $SEC 1
J 0
(-4950 5450);
DISPLAY 0.680851 (-4950 5450);
PAINT MONO (-4950 5450);
DISPLAY INVISIBLE (-4950 5450);
FORCEPROP 2 LAST CDS_SEC 1
J 0
(-4950 5450);
DISPLAY 1.021277 (-4950 5450);
DISPLAY INVISIBLE (-4950 5450);
FORCEPROP 1 LASTPIN (-5000 5350) $PN 1
J 0
(-4990 5330);
DISPLAY 0.489362 (-4990 5330);
FORCEPROP 1 LASTPIN (-5000 5150) $PN 2
J 0
(-4990 5130);
DISPLAY 0.489362 (-4990 5130);
FORCEPROP 1 LAST MATERIAL X6S
J 0
(-4950 5150);
DISPLAY 0.489362 (-4950 5150);
PAINT SKYBLUE (-4950 5150);
FORCEPROP 1 LAST TOLERANCE 20%
J 0
(-4950 5200);
DISPLAY 0.489362 (-4950 5200);
PAINT SKYBLUE (-4950 5200);
FORCEPROP 1 LAST VALUE 22UF
J 0
(-4950 5300);
DISPLAY 0.489362 (-4950 5300);
PAINT SKYBLUE (-4950 5300);
FORCEPROP 1 LAST VOLTAGE 4V
J 0
(-4950 5250);
DISPLAY 0.489362 (-4950 5250);
PAINT SKYBLUE (-4950 5250);
FORCEPROP 1 LAST PACK_TYPE C0402
J 0
(-4950 5050);
DISPLAY 0.489362 (-4950 5050);
PAINT SKYBLUE (-4950 5050);
FORCEPROP 2 LAST CDS_LIB pure_quanta
J 0
(-5000 5250);
PAINT MONO (-5000 5250);
DISPLAY INVISIBLE (-5000 5250);
FORCEPROP 1 LAST PATH I62
J 0
(-4950 5400);
DISPLAY 0.978723 (-4950 5400);
PAINT WHITE (-4950 5400);
DISPLAY INVISIBLE (-4950 5400);
FORCEPROP 1 LAST PART_NUMBER CH622KMEB02
J 0
(-4950 5100);
DISPLAY 0.489362 (-4950 5100);
PAINT SKYBLUE (-4950 5100);
DISPLAY INVISIBLE (-4950 5100);
FORCEADD Q_CAP..1
(-4425 5250);
FORCEPROP 1 LAST LOCATION C2201
J 0
(-4375 5350);
DISPLAY 0.489362 (-4375 5350);
PAINT SKYBLUE (-4375 5350);
FORCEPROP 2 LAST $SEC 1
J 0
(-4375 5450);
DISPLAY 0.680851 (-4375 5450);
PAINT MONO (-4375 5450);
DISPLAY INVISIBLE (-4375 5450);
FORCEPROP 2 LAST CDS_SEC 1
J 0
(-4375 5450);
DISPLAY 1.021277 (-4375 5450);
DISPLAY INVISIBLE (-4375 5450);
FORCEPROP 1 LASTPIN (-4425 5350) $PN 1
J 0
(-4415 5330);
DISPLAY 0.489362 (-4415 5330);
FORCEPROP 1 LASTPIN (-4425 5150) $PN 2
J 0
(-4415 5130);
DISPLAY 0.489362 (-4415 5130);
FORCEPROP 1 LAST MATERIAL X6S
J 0
(-4375 5150);
DISPLAY 0.489362 (-4375 5150);
PAINT SKYBLUE (-4375 5150);
FORCEPROP 1 LAST TOLERANCE 20%
J 0
(-4375 5200);
DISPLAY 0.489362 (-4375 5200);
PAINT SKYBLUE (-4375 5200);
FORCEPROP 1 LAST VALUE 22UF
J 0
(-4375 5300);
DISPLAY 0.489362 (-4375 5300);
PAINT SKYBLUE (-4375 5300);
FORCEPROP 1 LAST VOLTAGE 4V
J 0
(-4375 5250);
DISPLAY 0.489362 (-4375 5250);
PAINT SKYBLUE (-4375 5250);
FORCEPROP 1 LAST PACK_TYPE C0402
J 0
(-4375 5050);
DISPLAY 0.489362 (-4375 5050);
PAINT SKYBLUE (-4375 5050);
FORCEPROP 2 LAST CDS_LIB pure_quanta
J 0
(-4425 5250);
PAINT MONO (-4425 5250);
DISPLAY INVISIBLE (-4425 5250);
FORCEPROP 1 LAST PATH I63
J 0
(-4375 5400);
DISPLAY 0.978723 (-4375 5400);
PAINT WHITE (-4375 5400);
DISPLAY INVISIBLE (-4375 5400);
FORCEPROP 1 LAST PART_NUMBER CH622KMEB02
J 0
(-4375 5100);
DISPLAY 0.489362 (-4375 5100);
PAINT SKYBLUE (-4375 5100);
DISPLAY INVISIBLE (-4375 5100);
FORCEADD UNIVERSAL_POWER..1
(-4425 5525);
FORCEPROP 3 LASTPIN (-4425 5475) SIG_NAME PVDDCR_CPU1_P0\g
J 0
(-4415 5485);
DISPLAY 0.659574 (-4415 5485);
PAINT MONO (-4415 5485);
DISPLAY INVISIBLE (-4415 5485);
FORCEPROP 1 LAST HDL_POWER PVDDCR_CPU1_P0
J 1
(-4425 5575);
DISPLAY 0.489362 (-4425 5575);
PAINT GREEN (-4425 5575);
FORCEPROP 2 LAST CDS_LIB pure_quanta_power
J 0
(-4425 5525);
DISPLAY INVISIBLE (-4425 5525);
FORCEPROP 1 LAST PATH I64
J 0
(-4375 5550);
DISPLAY 0.872340 (-4375 5550);
PAINT AQUA (-4375 5550);
DISPLAY INVISIBLE (-4375 5550);
FORCEADD Q_CAP..1
(-3975 2075);
FORCEPROP 1 LAST LOCATION C2211
J 0
(-3925 2175);
DISPLAY 0.489362 (-3925 2175);
PAINT SKYBLUE (-3925 2175);
FORCEPROP 2 LAST $SEC 1
J 0
(-3925 2275);
DISPLAY 0.680851 (-3925 2275);
PAINT MONO (-3925 2275);
DISPLAY INVISIBLE (-3925 2275);
FORCEPROP 2 LAST CDS_SEC 1
J 0
(-3925 2275);
DISPLAY 1.021277 (-3925 2275);
DISPLAY INVISIBLE (-3925 2275);
FORCEPROP 1 LASTPIN (-3975 2175) $PN 1
J 0
(-3965 2155);
DISPLAY 0.489362 (-3965 2155);
FORCEPROP 1 LASTPIN (-3975 1975) $PN 2
J 0
(-3965 1955);
DISPLAY 0.489362 (-3965 1955);
FORCEPROP 1 LAST MATERIAL X6S
J 0
(-3925 1975);
DISPLAY 0.489362 (-3925 1975);
PAINT SKYBLUE (-3925 1975);
FORCEPROP 1 LAST TOLERANCE 20%
J 0
(-3925 2025);
DISPLAY 0.489362 (-3925 2025);
PAINT SKYBLUE (-3925 2025);
FORCEPROP 1 LAST VALUE 22UF
J 0
(-3925 2125);
DISPLAY 0.489362 (-3925 2125);
PAINT SKYBLUE (-3925 2125);
FORCEPROP 1 LAST VOLTAGE 4V
J 0
(-3925 2075);
DISPLAY 0.489362 (-3925 2075);
PAINT SKYBLUE (-3925 2075);
FORCEPROP 1 LAST PACK_TYPE C0402
J 0
(-3925 1875);
DISPLAY 0.489362 (-3925 1875);
PAINT SKYBLUE (-3925 1875);
FORCEPROP 2 LAST CDS_LIB pure_quanta
J 0
(-3975 2075);
PAINT MONO (-3975 2075);
DISPLAY INVISIBLE (-3975 2075);
FORCEPROP 1 LAST PATH I65
J 0
(-3925 2225);
DISPLAY 0.978723 (-3925 2225);
PAINT WHITE (-3925 2225);
DISPLAY INVISIBLE (-3925 2225);
FORCEPROP 1 LAST PART_NUMBER CH622KMEB02
J 0
(-3925 1925);
DISPLAY 0.489362 (-3925 1925);
PAINT SKYBLUE (-3925 1925);
DISPLAY INVISIBLE (-3925 1925);
FORCEADD Q_CAP..1
(-3525 2075);
FORCEPROP 1 LAST LOCATION C2217
J 0
(-3475 2175);
DISPLAY 0.489362 (-3475 2175);
PAINT SKYBLUE (-3475 2175);
FORCEPROP 2 LAST $SEC 1
J 0
(-3475 2275);
DISPLAY 0.680851 (-3475 2275);
PAINT MONO (-3475 2275);
DISPLAY INVISIBLE (-3475 2275);
FORCEPROP 2 LAST CDS_SEC 1
J 0
(-3475 2275);
DISPLAY 1.021277 (-3475 2275);
DISPLAY INVISIBLE (-3475 2275);
FORCEPROP 1 LASTPIN (-3525 2175) $PN 1
J 0
(-3515 2155);
DISPLAY 0.489362 (-3515 2155);
FORCEPROP 1 LASTPIN (-3525 1975) $PN 2
J 0
(-3515 1955);
DISPLAY 0.489362 (-3515 1955);
FORCEPROP 1 LAST MATERIAL X6S
J 0
(-3475 1975);
DISPLAY 0.489362 (-3475 1975);
PAINT SKYBLUE (-3475 1975);
FORCEPROP 1 LAST TOLERANCE 20%
J 0
(-3475 2025);
DISPLAY 0.489362 (-3475 2025);
PAINT SKYBLUE (-3475 2025);
FORCEPROP 1 LAST VALUE 22UF
J 0
(-3475 2125);
DISPLAY 0.489362 (-3475 2125);
PAINT SKYBLUE (-3475 2125);
FORCEPROP 1 LAST VOLTAGE 4V
J 0
(-3475 2075);
DISPLAY 0.489362 (-3475 2075);
PAINT SKYBLUE (-3475 2075);
FORCEPROP 1 LAST PACK_TYPE C0402
J 0
(-3475 1875);
DISPLAY 0.489362 (-3475 1875);
PAINT SKYBLUE (-3475 1875);
FORCEPROP 2 LAST CDS_LIB pure_quanta
J 0
(-3525 2075);
PAINT MONO (-3525 2075);
DISPLAY INVISIBLE (-3525 2075);
FORCEPROP 1 LAST PATH I66
J 0
(-3475 2225);
DISPLAY 0.978723 (-3475 2225);
PAINT WHITE (-3475 2225);
DISPLAY INVISIBLE (-3475 2225);
FORCEPROP 1 LAST PART_NUMBER CH622KMEB02
J 0
(-3475 1925);
DISPLAY 0.489362 (-3475 1925);
PAINT SKYBLUE (-3475 1925);
DISPLAY INVISIBLE (-3475 1925);
FORCEADD Q_CAP..1
(-3075 2075);
FORCEPROP 1 LAST LOCATION C2223
J 0
(-3025 2175);
DISPLAY 0.489362 (-3025 2175);
PAINT SKYBLUE (-3025 2175);
FORCEPROP 2 LAST $SEC 1
J 0
(-3025 2275);
DISPLAY 0.680851 (-3025 2275);
PAINT MONO (-3025 2275);
DISPLAY INVISIBLE (-3025 2275);
FORCEPROP 2 LAST CDS_SEC 1
J 0
(-3025 2275);
DISPLAY 1.021277 (-3025 2275);
DISPLAY INVISIBLE (-3025 2275);
FORCEPROP 1 LASTPIN (-3075 2175) $PN 1
J 0
(-3065 2155);
DISPLAY 0.489362 (-3065 2155);
FORCEPROP 1 LASTPIN (-3075 1975) $PN 2
J 0
(-3065 1955);
DISPLAY 0.489362 (-3065 1955);
FORCEPROP 1 LAST MATERIAL X6S
J 0
(-3025 1975);
DISPLAY 0.489362 (-3025 1975);
PAINT SKYBLUE (-3025 1975);
FORCEPROP 1 LAST TOLERANCE 20%
J 0
(-3025 2025);
DISPLAY 0.489362 (-3025 2025);
PAINT SKYBLUE (-3025 2025);
FORCEPROP 1 LAST VALUE 22UF
J 0
(-3025 2125);
DISPLAY 0.489362 (-3025 2125);
PAINT SKYBLUE (-3025 2125);
FORCEPROP 1 LAST VOLTAGE 4V
J 0
(-3025 2075);
DISPLAY 0.489362 (-3025 2075);
PAINT SKYBLUE (-3025 2075);
FORCEPROP 1 LAST PACK_TYPE C0402
J 0
(-3025 1875);
DISPLAY 0.489362 (-3025 1875);
PAINT SKYBLUE (-3025 1875);
FORCEPROP 2 LAST CDS_LIB pure_quanta
J 0
(-3075 2075);
PAINT MONO (-3075 2075);
DISPLAY INVISIBLE (-3075 2075);
FORCEPROP 1 LAST PATH I67
J 0
(-3025 2225);
DISPLAY 0.978723 (-3025 2225);
PAINT WHITE (-3025 2225);
DISPLAY INVISIBLE (-3025 2225);
FORCEPROP 1 LAST PART_NUMBER CH622KMEB02
J 0
(-3025 1925);
DISPLAY 0.489362 (-3025 1925);
PAINT SKYBLUE (-3025 1925);
DISPLAY INVISIBLE (-3025 1925);
FORCEADD UNIVERSAL_GND..1
(-2625 1725);
FORCEPROP 3 LASTPIN (-2625 1775) SIG_NAME GND\g
J 0
(-2615 1785);
DISPLAY 0.659574 (-2615 1785);
PAINT MONO (-2615 1785);
DISPLAY INVISIBLE (-2615 1785);
FORCEPROP 2 LAST CDS_LIB pure_quanta_power
J 0
(-2625 1725);
PAINT MONO (-2625 1725);
DISPLAY INVISIBLE (-2625 1725);
FORCEPROP 1 LAST HDL_POWER GND
J 1
(-2600 1650);
DISPLAY 0.872340 (-2600 1650);
PAINT GREEN (-2600 1650);
DISPLAY INVISIBLE (-2600 1650);
FORCEPROP 1 LAST PATH I68
J 0
(-2550 1725);
DISPLAY 0.872340 (-2550 1725);
PAINT AQUA (-2550 1725);
DISPLAY INVISIBLE (-2550 1725);
FORCEADD Q_CAP..1
(-2625 2075);
FORCEPROP 1 LAST LOCATION C2229
J 0
(-2575 2175);
DISPLAY 0.489362 (-2575 2175);
PAINT SKYBLUE (-2575 2175);
FORCEPROP 2 LAST $SEC 1
J 0
(-2575 2275);
DISPLAY 0.680851 (-2575 2275);
PAINT MONO (-2575 2275);
DISPLAY INVISIBLE (-2575 2275);
FORCEPROP 2 LAST CDS_SEC 1
J 0
(-2575 2275);
DISPLAY 1.021277 (-2575 2275);
DISPLAY INVISIBLE (-2575 2275);
FORCEPROP 1 LASTPIN (-2625 2175) $PN 1
J 0
(-2615 2155);
DISPLAY 0.489362 (-2615 2155);
FORCEPROP 1 LASTPIN (-2625 1975) $PN 2
J 0
(-2615 1955);
DISPLAY 0.489362 (-2615 1955);
FORCEPROP 1 LAST MATERIAL X6S
J 0
(-2575 1975);
DISPLAY 0.489362 (-2575 1975);
PAINT SKYBLUE (-2575 1975);
FORCEPROP 1 LAST TOLERANCE 20%
J 0
(-2575 2025);
DISPLAY 0.489362 (-2575 2025);
PAINT SKYBLUE (-2575 2025);
FORCEPROP 1 LAST VALUE 22UF
J 0
(-2575 2125);
DISPLAY 0.489362 (-2575 2125);
PAINT SKYBLUE (-2575 2125);
FORCEPROP 1 LAST VOLTAGE 4V
J 0
(-2575 2075);
DISPLAY 0.489362 (-2575 2075);
PAINT SKYBLUE (-2575 2075);
FORCEPROP 1 LAST PACK_TYPE C0402
J 0
(-2575 1875);
DISPLAY 0.489362 (-2575 1875);
PAINT SKYBLUE (-2575 1875);
FORCEPROP 2 LAST CDS_LIB pure_quanta
J 0
(-2625 2075);
PAINT MONO (-2625 2075);
DISPLAY INVISIBLE (-2625 2075);
FORCEPROP 1 LAST PATH I69
J 0
(-2575 2225);
DISPLAY 0.978723 (-2575 2225);
PAINT WHITE (-2575 2225);
DISPLAY INVISIBLE (-2575 2225);
FORCEPROP 1 LAST PART_NUMBER CH622KMEB02
J 0
(-2575 1925);
DISPLAY 0.489362 (-2575 1925);
PAINT SKYBLUE (-2575 1925);
DISPLAY INVISIBLE (-2575 1925);
FORCEADD Q_CAP..1
(-9000 3675);
FORCEPROP 1 LAST LOCATION C2165
J 0
(-8950 3775);
DISPLAY 0.489362 (-8950 3775);
PAINT SKYBLUE (-8950 3775);
FORCEPROP 2 LAST $SEC 1
J 0
(-8950 3875);
DISPLAY 0.680851 (-8950 3875);
PAINT MONO (-8950 3875);
DISPLAY INVISIBLE (-8950 3875);
FORCEPROP 2 LAST CDS_SEC 1
J 0
(-8950 3875);
DISPLAY 1.021277 (-8950 3875);
DISPLAY INVISIBLE (-8950 3875);
FORCEPROP 1 LASTPIN (-9000 3775) $PN 1
J 0
(-8990 3755);
DISPLAY 0.489362 (-8990 3755);
FORCEPROP 1 LASTPIN (-9000 3575) $PN 2
J 0
(-8990 3555);
DISPLAY 0.489362 (-8990 3555);
FORCEPROP 1 LAST MATERIAL X6S
J 0
(-8950 3575);
DISPLAY 0.489362 (-8950 3575);
PAINT SKYBLUE (-8950 3575);
FORCEPROP 1 LAST TOLERANCE 20%
J 0
(-8950 3625);
DISPLAY 0.489362 (-8950 3625);
PAINT SKYBLUE (-8950 3625);
FORCEPROP 1 LAST VALUE 22UF
J 0
(-8950 3725);
DISPLAY 0.489362 (-8950 3725);
PAINT SKYBLUE (-8950 3725);
FORCEPROP 1 LAST VOLTAGE 4V
J 0
(-8950 3675);
DISPLAY 0.489362 (-8950 3675);
PAINT SKYBLUE (-8950 3675);
FORCEPROP 1 LAST PACK_TYPE C0402
J 0
(-8950 3475);
DISPLAY 0.489362 (-8950 3475);
PAINT SKYBLUE (-8950 3475);
FORCEPROP 2 LAST CDS_LIB pure_quanta
J 0
(-9000 3675);
PAINT MONO (-9000 3675);
DISPLAY INVISIBLE (-9000 3675);
FORCEPROP 1 LAST PATH I7
J 0
(-8950 3825);
DISPLAY 0.978723 (-8950 3825);
PAINT WHITE (-8950 3825);
DISPLAY INVISIBLE (-8950 3825);
FORCEPROP 1 LAST PART_NUMBER CH622KMEB02
J 0
(-8950 3525);
DISPLAY 0.489362 (-8950 3525);
PAINT SKYBLUE (-8950 3525);
DISPLAY INVISIBLE (-8950 3525);
FORCEADD Q_CAP..1
(-3975 2875);
FORCEPROP 1 LAST LOCATION C2210
J 0
(-3925 2975);
DISPLAY 0.489362 (-3925 2975);
PAINT SKYBLUE (-3925 2975);
FORCEPROP 2 LAST $SEC 1
J 0
(-3925 3075);
DISPLAY 0.680851 (-3925 3075);
PAINT MONO (-3925 3075);
DISPLAY INVISIBLE (-3925 3075);
FORCEPROP 2 LAST CDS_SEC 1
J 0
(-3925 3075);
DISPLAY 1.021277 (-3925 3075);
DISPLAY INVISIBLE (-3925 3075);
FORCEPROP 1 LASTPIN (-3975 2975) $PN 1
J 0
(-3965 2955);
DISPLAY 0.489362 (-3965 2955);
FORCEPROP 1 LASTPIN (-3975 2775) $PN 2
J 0
(-3965 2755);
DISPLAY 0.489362 (-3965 2755);
FORCEPROP 1 LAST MATERIAL X6S
J 0
(-3925 2775);
DISPLAY 0.489362 (-3925 2775);
PAINT SKYBLUE (-3925 2775);
FORCEPROP 1 LAST TOLERANCE 20%
J 0
(-3925 2825);
DISPLAY 0.489362 (-3925 2825);
PAINT SKYBLUE (-3925 2825);
FORCEPROP 1 LAST VALUE 22UF
J 0
(-3925 2925);
DISPLAY 0.489362 (-3925 2925);
PAINT SKYBLUE (-3925 2925);
FORCEPROP 1 LAST VOLTAGE 4V
J 0
(-3925 2875);
DISPLAY 0.489362 (-3925 2875);
PAINT SKYBLUE (-3925 2875);
FORCEPROP 1 LAST PACK_TYPE C0402
J 0
(-3925 2675);
DISPLAY 0.489362 (-3925 2675);
PAINT SKYBLUE (-3925 2675);
FORCEPROP 2 LAST CDS_LIB pure_quanta
J 0
(-3975 2875);
PAINT MONO (-3975 2875);
DISPLAY INVISIBLE (-3975 2875);
FORCEPROP 1 LAST PATH I70
J 0
(-3925 3025);
DISPLAY 0.978723 (-3925 3025);
PAINT WHITE (-3925 3025);
DISPLAY INVISIBLE (-3925 3025);
FORCEPROP 1 LAST PART_NUMBER CH622KMEB02
J 0
(-3925 2725);
DISPLAY 0.489362 (-3925 2725);
PAINT SKYBLUE (-3925 2725);
DISPLAY INVISIBLE (-3925 2725);
FORCEADD Q_CAP..1
(-3525 2875);
FORCEPROP 1 LAST LOCATION C2216
J 0
(-3475 2975);
DISPLAY 0.489362 (-3475 2975);
PAINT SKYBLUE (-3475 2975);
FORCEPROP 2 LAST $SEC 1
J 0
(-3475 3075);
DISPLAY 0.680851 (-3475 3075);
PAINT MONO (-3475 3075);
DISPLAY INVISIBLE (-3475 3075);
FORCEPROP 2 LAST CDS_SEC 1
J 0
(-3475 3075);
DISPLAY 1.021277 (-3475 3075);
DISPLAY INVISIBLE (-3475 3075);
FORCEPROP 1 LASTPIN (-3525 2975) $PN 1
J 0
(-3515 2955);
DISPLAY 0.489362 (-3515 2955);
FORCEPROP 1 LASTPIN (-3525 2775) $PN 2
J 0
(-3515 2755);
DISPLAY 0.489362 (-3515 2755);
FORCEPROP 1 LAST MATERIAL X6S
J 0
(-3475 2775);
DISPLAY 0.489362 (-3475 2775);
PAINT SKYBLUE (-3475 2775);
FORCEPROP 1 LAST TOLERANCE 20%
J 0
(-3475 2825);
DISPLAY 0.489362 (-3475 2825);
PAINT SKYBLUE (-3475 2825);
FORCEPROP 1 LAST VALUE 22UF
J 0
(-3475 2925);
DISPLAY 0.489362 (-3475 2925);
PAINT SKYBLUE (-3475 2925);
FORCEPROP 1 LAST VOLTAGE 4V
J 0
(-3475 2875);
DISPLAY 0.489362 (-3475 2875);
PAINT SKYBLUE (-3475 2875);
FORCEPROP 1 LAST PACK_TYPE C0402
J 0
(-3475 2675);
DISPLAY 0.489362 (-3475 2675);
PAINT SKYBLUE (-3475 2675);
FORCEPROP 2 LAST CDS_LIB pure_quanta
J 0
(-3525 2875);
PAINT MONO (-3525 2875);
DISPLAY INVISIBLE (-3525 2875);
FORCEPROP 1 LAST PATH I71
J 0
(-3475 3025);
DISPLAY 0.978723 (-3475 3025);
PAINT WHITE (-3475 3025);
DISPLAY INVISIBLE (-3475 3025);
FORCEPROP 1 LAST PART_NUMBER CH622KMEB02
J 0
(-3475 2725);
DISPLAY 0.489362 (-3475 2725);
PAINT SKYBLUE (-3475 2725);
DISPLAY INVISIBLE (-3475 2725);
FORCEADD Q_CAP..1
(-3975 3675);
FORCEPROP 1 LAST LOCATION C2209
J 0
(-3925 3775);
DISPLAY 0.489362 (-3925 3775);
PAINT SKYBLUE (-3925 3775);
FORCEPROP 2 LAST $SEC 1
J 0
(-3925 3875);
DISPLAY 0.680851 (-3925 3875);
PAINT MONO (-3925 3875);
DISPLAY INVISIBLE (-3925 3875);
FORCEPROP 2 LAST CDS_SEC 1
J 0
(-3925 3875);
DISPLAY 1.021277 (-3925 3875);
DISPLAY INVISIBLE (-3925 3875);
FORCEPROP 1 LASTPIN (-3975 3775) $PN 1
J 0
(-3965 3755);
DISPLAY 0.489362 (-3965 3755);
FORCEPROP 1 LASTPIN (-3975 3575) $PN 2
J 0
(-3965 3555);
DISPLAY 0.489362 (-3965 3555);
FORCEPROP 1 LAST MATERIAL X6S
J 0
(-3925 3575);
DISPLAY 0.489362 (-3925 3575);
PAINT SKYBLUE (-3925 3575);
FORCEPROP 1 LAST TOLERANCE 20%
J 0
(-3925 3625);
DISPLAY 0.489362 (-3925 3625);
PAINT SKYBLUE (-3925 3625);
FORCEPROP 1 LAST VALUE 22UF
J 0
(-3925 3725);
DISPLAY 0.489362 (-3925 3725);
PAINT SKYBLUE (-3925 3725);
FORCEPROP 1 LAST VOLTAGE 4V
J 0
(-3925 3675);
DISPLAY 0.489362 (-3925 3675);
PAINT SKYBLUE (-3925 3675);
FORCEPROP 1 LAST PACK_TYPE C0402
J 0
(-3925 3475);
DISPLAY 0.489362 (-3925 3475);
PAINT SKYBLUE (-3925 3475);
FORCEPROP 2 LAST CDS_LIB pure_quanta
J 0
(-3975 3675);
PAINT MONO (-3975 3675);
DISPLAY INVISIBLE (-3975 3675);
FORCEPROP 1 LAST PATH I72
J 0
(-3925 3825);
DISPLAY 0.978723 (-3925 3825);
PAINT WHITE (-3925 3825);
DISPLAY INVISIBLE (-3925 3825);
FORCEPROP 1 LAST PART_NUMBER CH622KMEB02
J 0
(-3925 3525);
DISPLAY 0.489362 (-3925 3525);
PAINT SKYBLUE (-3925 3525);
DISPLAY INVISIBLE (-3925 3525);
FORCEADD Q_CAP..1
(-3525 3675);
FORCEPROP 1 LAST LOCATION C2215
J 0
(-3475 3775);
DISPLAY 0.489362 (-3475 3775);
PAINT SKYBLUE (-3475 3775);
FORCEPROP 2 LAST $SEC 1
J 0
(-3475 3875);
DISPLAY 0.680851 (-3475 3875);
PAINT MONO (-3475 3875);
DISPLAY INVISIBLE (-3475 3875);
FORCEPROP 2 LAST CDS_SEC 1
J 0
(-3475 3875);
DISPLAY 1.021277 (-3475 3875);
DISPLAY INVISIBLE (-3475 3875);
FORCEPROP 1 LASTPIN (-3525 3775) $PN 1
J 0
(-3515 3755);
DISPLAY 0.489362 (-3515 3755);
FORCEPROP 1 LASTPIN (-3525 3575) $PN 2
J 0
(-3515 3555);
DISPLAY 0.489362 (-3515 3555);
FORCEPROP 1 LAST MATERIAL X6S
J 0
(-3475 3575);
DISPLAY 0.489362 (-3475 3575);
PAINT SKYBLUE (-3475 3575);
FORCEPROP 1 LAST TOLERANCE 20%
J 0
(-3475 3625);
DISPLAY 0.489362 (-3475 3625);
PAINT SKYBLUE (-3475 3625);
FORCEPROP 1 LAST VALUE 22UF
J 0
(-3475 3725);
DISPLAY 0.489362 (-3475 3725);
PAINT SKYBLUE (-3475 3725);
FORCEPROP 1 LAST VOLTAGE 4V
J 0
(-3475 3675);
DISPLAY 0.489362 (-3475 3675);
PAINT SKYBLUE (-3475 3675);
FORCEPROP 1 LAST PACK_TYPE C0402
J 0
(-3475 3475);
DISPLAY 0.489362 (-3475 3475);
PAINT SKYBLUE (-3475 3475);
FORCEPROP 2 LAST CDS_LIB pure_quanta
J 0
(-3525 3675);
PAINT MONO (-3525 3675);
DISPLAY INVISIBLE (-3525 3675);
FORCEPROP 1 LAST PATH I73
J 0
(-3475 3825);
DISPLAY 0.978723 (-3475 3825);
PAINT WHITE (-3475 3825);
DISPLAY INVISIBLE (-3475 3825);
FORCEPROP 1 LAST PART_NUMBER CH622KMEB02
J 0
(-3475 3525);
DISPLAY 0.489362 (-3475 3525);
PAINT SKYBLUE (-3475 3525);
DISPLAY INVISIBLE (-3475 3525);
FORCEADD Q_CAP..1
(-3075 2875);
FORCEPROP 1 LAST LOCATION C2222
J 0
(-3025 2975);
DISPLAY 0.489362 (-3025 2975);
PAINT SKYBLUE (-3025 2975);
FORCEPROP 2 LAST $SEC 1
J 0
(-3025 3075);
DISPLAY 0.680851 (-3025 3075);
PAINT MONO (-3025 3075);
DISPLAY INVISIBLE (-3025 3075);
FORCEPROP 2 LAST CDS_SEC 1
J 0
(-3025 3075);
DISPLAY 1.021277 (-3025 3075);
DISPLAY INVISIBLE (-3025 3075);
FORCEPROP 1 LASTPIN (-3075 2975) $PN 1
J 0
(-3065 2955);
DISPLAY 0.489362 (-3065 2955);
FORCEPROP 1 LASTPIN (-3075 2775) $PN 2
J 0
(-3065 2755);
DISPLAY 0.489362 (-3065 2755);
FORCEPROP 1 LAST MATERIAL X6S
J 0
(-3025 2775);
DISPLAY 0.489362 (-3025 2775);
PAINT SKYBLUE (-3025 2775);
FORCEPROP 1 LAST TOLERANCE 20%
J 0
(-3025 2825);
DISPLAY 0.489362 (-3025 2825);
PAINT SKYBLUE (-3025 2825);
FORCEPROP 1 LAST VALUE 22UF
J 0
(-3025 2925);
DISPLAY 0.489362 (-3025 2925);
PAINT SKYBLUE (-3025 2925);
FORCEPROP 1 LAST VOLTAGE 4V
J 0
(-3025 2875);
DISPLAY 0.489362 (-3025 2875);
PAINT SKYBLUE (-3025 2875);
FORCEPROP 1 LAST PACK_TYPE C0402
J 0
(-3025 2675);
DISPLAY 0.489362 (-3025 2675);
PAINT SKYBLUE (-3025 2675);
FORCEPROP 2 LAST CDS_LIB pure_quanta
J 0
(-3075 2875);
PAINT MONO (-3075 2875);
DISPLAY INVISIBLE (-3075 2875);
FORCEPROP 1 LAST PATH I74
J 0
(-3025 3025);
DISPLAY 0.978723 (-3025 3025);
PAINT WHITE (-3025 3025);
DISPLAY INVISIBLE (-3025 3025);
FORCEPROP 1 LAST PART_NUMBER CH622KMEB02
J 0
(-3025 2725);
DISPLAY 0.489362 (-3025 2725);
PAINT SKYBLUE (-3025 2725);
DISPLAY INVISIBLE (-3025 2725);
FORCEADD Q_CAP..1
(-2625 2875);
FORCEPROP 1 LAST LOCATION C2228
J 0
(-2575 2975);
DISPLAY 0.489362 (-2575 2975);
PAINT SKYBLUE (-2575 2975);
FORCEPROP 2 LAST $SEC 1
J 0
(-2575 3075);
DISPLAY 0.680851 (-2575 3075);
PAINT MONO (-2575 3075);
DISPLAY INVISIBLE (-2575 3075);
FORCEPROP 2 LAST CDS_SEC 1
J 0
(-2575 3075);
DISPLAY 1.021277 (-2575 3075);
DISPLAY INVISIBLE (-2575 3075);
FORCEPROP 1 LASTPIN (-2625 2975) $PN 1
J 0
(-2615 2955);
DISPLAY 0.489362 (-2615 2955);
FORCEPROP 1 LASTPIN (-2625 2775) $PN 2
J 0
(-2615 2755);
DISPLAY 0.489362 (-2615 2755);
FORCEPROP 1 LAST MATERIAL X6S
J 0
(-2575 2775);
DISPLAY 0.489362 (-2575 2775);
PAINT SKYBLUE (-2575 2775);
FORCEPROP 1 LAST TOLERANCE 20%
J 0
(-2575 2825);
DISPLAY 0.489362 (-2575 2825);
PAINT SKYBLUE (-2575 2825);
FORCEPROP 1 LAST VALUE 22UF
J 0
(-2575 2925);
DISPLAY 0.489362 (-2575 2925);
PAINT SKYBLUE (-2575 2925);
FORCEPROP 1 LAST VOLTAGE 4V
J 0
(-2575 2875);
DISPLAY 0.489362 (-2575 2875);
PAINT SKYBLUE (-2575 2875);
FORCEPROP 1 LAST PACK_TYPE C0402
J 0
(-2575 2675);
DISPLAY 0.489362 (-2575 2675);
PAINT SKYBLUE (-2575 2675);
FORCEPROP 2 LAST CDS_LIB pure_quanta
J 0
(-2625 2875);
PAINT MONO (-2625 2875);
DISPLAY INVISIBLE (-2625 2875);
FORCEPROP 1 LAST PATH I75
J 0
(-2575 3025);
DISPLAY 0.978723 (-2575 3025);
PAINT WHITE (-2575 3025);
DISPLAY INVISIBLE (-2575 3025);
FORCEPROP 1 LAST PART_NUMBER CH622KMEB02
J 0
(-2575 2725);
DISPLAY 0.489362 (-2575 2725);
PAINT SKYBLUE (-2575 2725);
DISPLAY INVISIBLE (-2575 2725);
FORCEADD Q_CAP..1
(-2175 2875);
FORCEPROP 1 LAST LOCATION C2234
J 0
(-2125 2975);
DISPLAY 0.489362 (-2125 2975);
PAINT SKYBLUE (-2125 2975);
FORCEPROP 2 LAST $SEC 1
J 0
(-2125 3075);
DISPLAY 0.680851 (-2125 3075);
PAINT MONO (-2125 3075);
DISPLAY INVISIBLE (-2125 3075);
FORCEPROP 2 LAST CDS_SEC 1
J 0
(-2125 3075);
DISPLAY 1.021277 (-2125 3075);
DISPLAY INVISIBLE (-2125 3075);
FORCEPROP 1 LASTPIN (-2175 2975) $PN 1
J 0
(-2165 2955);
DISPLAY 0.489362 (-2165 2955);
FORCEPROP 1 LASTPIN (-2175 2775) $PN 2
J 0
(-2165 2755);
DISPLAY 0.489362 (-2165 2755);
FORCEPROP 1 LAST MATERIAL X6S
J 0
(-2125 2775);
DISPLAY 0.489362 (-2125 2775);
PAINT SKYBLUE (-2125 2775);
FORCEPROP 1 LAST TOLERANCE 20%
J 0
(-2125 2825);
DISPLAY 0.489362 (-2125 2825);
PAINT SKYBLUE (-2125 2825);
FORCEPROP 1 LAST VALUE 22UF
J 0
(-2125 2925);
DISPLAY 0.489362 (-2125 2925);
PAINT SKYBLUE (-2125 2925);
FORCEPROP 1 LAST VOLTAGE 4V
J 0
(-2125 2875);
DISPLAY 0.489362 (-2125 2875);
PAINT SKYBLUE (-2125 2875);
FORCEPROP 1 LAST PACK_TYPE C0402
J 0
(-2125 2675);
DISPLAY 0.489362 (-2125 2675);
PAINT SKYBLUE (-2125 2675);
FORCEPROP 2 LAST CDS_LIB pure_quanta
J 0
(-2175 2875);
PAINT MONO (-2175 2875);
DISPLAY INVISIBLE (-2175 2875);
FORCEPROP 1 LAST PATH I76
J 0
(-2125 3025);
DISPLAY 0.978723 (-2125 3025);
PAINT WHITE (-2125 3025);
DISPLAY INVISIBLE (-2125 3025);
FORCEPROP 1 LAST PART_NUMBER CH622KMEB02
J 0
(-2125 2725);
DISPLAY 0.489362 (-2125 2725);
PAINT SKYBLUE (-2125 2725);
DISPLAY INVISIBLE (-2125 2725);
FORCEADD Q_CAP..1
(-3075 3675);
FORCEPROP 1 LAST LOCATION C2221
J 0
(-3025 3775);
DISPLAY 0.489362 (-3025 3775);
PAINT SKYBLUE (-3025 3775);
FORCEPROP 2 LAST $SEC 1
J 0
(-3025 3875);
DISPLAY 0.680851 (-3025 3875);
PAINT MONO (-3025 3875);
DISPLAY INVISIBLE (-3025 3875);
FORCEPROP 2 LAST CDS_SEC 1
J 0
(-3025 3875);
DISPLAY 1.021277 (-3025 3875);
DISPLAY INVISIBLE (-3025 3875);
FORCEPROP 1 LASTPIN (-3075 3775) $PN 1
J 0
(-3065 3755);
DISPLAY 0.489362 (-3065 3755);
FORCEPROP 1 LASTPIN (-3075 3575) $PN 2
J 0
(-3065 3555);
DISPLAY 0.489362 (-3065 3555);
FORCEPROP 1 LAST MATERIAL X6S
J 0
(-3025 3575);
DISPLAY 0.489362 (-3025 3575);
PAINT SKYBLUE (-3025 3575);
FORCEPROP 1 LAST TOLERANCE 20%
J 0
(-3025 3625);
DISPLAY 0.489362 (-3025 3625);
PAINT SKYBLUE (-3025 3625);
FORCEPROP 1 LAST VALUE 22UF
J 0
(-3025 3725);
DISPLAY 0.489362 (-3025 3725);
PAINT SKYBLUE (-3025 3725);
FORCEPROP 1 LAST VOLTAGE 4V
J 0
(-3025 3675);
DISPLAY 0.489362 (-3025 3675);
PAINT SKYBLUE (-3025 3675);
FORCEPROP 1 LAST PACK_TYPE C0402
J 0
(-3025 3475);
DISPLAY 0.489362 (-3025 3475);
PAINT SKYBLUE (-3025 3475);
FORCEPROP 2 LAST CDS_LIB pure_quanta
J 0
(-3075 3675);
PAINT MONO (-3075 3675);
DISPLAY INVISIBLE (-3075 3675);
FORCEPROP 1 LAST PATH I77
J 0
(-3025 3825);
DISPLAY 0.978723 (-3025 3825);
PAINT WHITE (-3025 3825);
DISPLAY INVISIBLE (-3025 3825);
FORCEPROP 1 LAST PART_NUMBER CH622KMEB02
J 0
(-3025 3525);
DISPLAY 0.489362 (-3025 3525);
PAINT SKYBLUE (-3025 3525);
DISPLAY INVISIBLE (-3025 3525);
FORCEADD Q_CAP..1
(-2625 3675);
FORCEPROP 1 LAST LOCATION C2227
J 0
(-2575 3775);
DISPLAY 0.489362 (-2575 3775);
PAINT SKYBLUE (-2575 3775);
FORCEPROP 2 LAST $SEC 1
J 0
(-2575 3875);
DISPLAY 0.680851 (-2575 3875);
PAINT MONO (-2575 3875);
DISPLAY INVISIBLE (-2575 3875);
FORCEPROP 2 LAST CDS_SEC 1
J 0
(-2575 3875);
DISPLAY 1.021277 (-2575 3875);
DISPLAY INVISIBLE (-2575 3875);
FORCEPROP 1 LASTPIN (-2625 3775) $PN 1
J 0
(-2615 3755);
DISPLAY 0.489362 (-2615 3755);
FORCEPROP 1 LASTPIN (-2625 3575) $PN 2
J 0
(-2615 3555);
DISPLAY 0.489362 (-2615 3555);
FORCEPROP 1 LAST MATERIAL X6S
J 0
(-2575 3575);
DISPLAY 0.489362 (-2575 3575);
PAINT SKYBLUE (-2575 3575);
FORCEPROP 1 LAST TOLERANCE 20%
J 0
(-2575 3625);
DISPLAY 0.489362 (-2575 3625);
PAINT SKYBLUE (-2575 3625);
FORCEPROP 1 LAST VALUE 22UF
J 0
(-2575 3725);
DISPLAY 0.489362 (-2575 3725);
PAINT SKYBLUE (-2575 3725);
FORCEPROP 1 LAST VOLTAGE 4V
J 0
(-2575 3675);
DISPLAY 0.489362 (-2575 3675);
PAINT SKYBLUE (-2575 3675);
FORCEPROP 1 LAST PACK_TYPE C0402
J 0
(-2575 3475);
DISPLAY 0.489362 (-2575 3475);
PAINT SKYBLUE (-2575 3475);
FORCEPROP 2 LAST CDS_LIB pure_quanta
J 0
(-2625 3675);
PAINT MONO (-2625 3675);
DISPLAY INVISIBLE (-2625 3675);
FORCEPROP 1 LAST PATH I78
J 0
(-2575 3825);
DISPLAY 0.978723 (-2575 3825);
PAINT WHITE (-2575 3825);
DISPLAY INVISIBLE (-2575 3825);
FORCEPROP 1 LAST PART_NUMBER CH622KMEB02
J 0
(-2575 3525);
DISPLAY 0.489362 (-2575 3525);
PAINT SKYBLUE (-2575 3525);
DISPLAY INVISIBLE (-2575 3525);
FORCEADD Q_CAP..1
(-2175 3675);
FORCEPROP 1 LAST LOCATION C2233
J 0
(-2125 3775);
DISPLAY 0.489362 (-2125 3775);
PAINT SKYBLUE (-2125 3775);
FORCEPROP 2 LAST $SEC 1
J 0
(-2125 3875);
DISPLAY 0.680851 (-2125 3875);
PAINT MONO (-2125 3875);
DISPLAY INVISIBLE (-2125 3875);
FORCEPROP 2 LAST CDS_SEC 1
J 0
(-2125 3875);
DISPLAY 1.021277 (-2125 3875);
DISPLAY INVISIBLE (-2125 3875);
FORCEPROP 1 LASTPIN (-2175 3775) $PN 1
J 0
(-2165 3755);
DISPLAY 0.489362 (-2165 3755);
FORCEPROP 1 LASTPIN (-2175 3575) $PN 2
J 0
(-2165 3555);
DISPLAY 0.489362 (-2165 3555);
FORCEPROP 1 LAST MATERIAL X6S
J 0
(-2125 3575);
DISPLAY 0.489362 (-2125 3575);
PAINT SKYBLUE (-2125 3575);
FORCEPROP 1 LAST TOLERANCE 20%
J 0
(-2125 3625);
DISPLAY 0.489362 (-2125 3625);
PAINT SKYBLUE (-2125 3625);
FORCEPROP 1 LAST VALUE 22UF
J 0
(-2125 3725);
DISPLAY 0.489362 (-2125 3725);
PAINT SKYBLUE (-2125 3725);
FORCEPROP 1 LAST VOLTAGE 4V
J 0
(-2125 3675);
DISPLAY 0.489362 (-2125 3675);
PAINT SKYBLUE (-2125 3675);
FORCEPROP 1 LAST PACK_TYPE C0402
J 0
(-2125 3475);
DISPLAY 0.489362 (-2125 3475);
PAINT SKYBLUE (-2125 3475);
FORCEPROP 2 LAST CDS_LIB pure_quanta
J 0
(-2175 3675);
PAINT MONO (-2175 3675);
DISPLAY INVISIBLE (-2175 3675);
FORCEPROP 1 LAST PATH I79
J 0
(-2125 3825);
DISPLAY 0.978723 (-2125 3825);
PAINT WHITE (-2125 3825);
DISPLAY INVISIBLE (-2125 3825);
FORCEPROP 1 LAST PART_NUMBER CH622KMEB02
J 0
(-2125 3525);
DISPLAY 0.489362 (-2125 3525);
PAINT SKYBLUE (-2125 3525);
DISPLAY INVISIBLE (-2125 3525);
FORCEADD UNIVERSAL_POWER..1
(-9000 3950);
FORCEPROP 3 LASTPIN (-9000 3900) SIG_NAME PVDDCR_CPU0_P0\g
J 0
(-8990 3910);
DISPLAY 0.659574 (-8990 3910);
PAINT MONO (-8990 3910);
DISPLAY INVISIBLE (-8990 3910);
FORCEPROP 1 LAST HDL_POWER PVDDCR_CPU0_P0
J 1
(-9000 4000);
DISPLAY 0.489362 (-9000 4000);
PAINT GREEN (-9000 4000);
FORCEPROP 2 LAST CDS_LIB pure_quanta_power
J 0
(-9000 3950);
DISPLAY INVISIBLE (-9000 3950);
FORCEPROP 1 LAST PATH I8
J 0
(-8950 3975);
DISPLAY 0.872340 (-8950 3975);
PAINT AQUA (-8950 3975);
DISPLAY INVISIBLE (-8950 3975);
FORCEADD Q_CAP..1
(-1725 2875);
FORCEPROP 1 LAST LOCATION C2240
J 0
(-1675 2975);
DISPLAY 0.489362 (-1675 2975);
PAINT SKYBLUE (-1675 2975);
FORCEPROP 2 LAST $SEC 1
J 0
(-1675 3075);
DISPLAY 0.680851 (-1675 3075);
PAINT MONO (-1675 3075);
DISPLAY INVISIBLE (-1675 3075);
FORCEPROP 2 LAST CDS_SEC 1
J 0
(-1675 3075);
DISPLAY 1.021277 (-1675 3075);
DISPLAY INVISIBLE (-1675 3075);
FORCEPROP 1 LASTPIN (-1725 2975) $PN 1
J 0
(-1715 2955);
DISPLAY 0.489362 (-1715 2955);
FORCEPROP 1 LASTPIN (-1725 2775) $PN 2
J 0
(-1715 2755);
DISPLAY 0.489362 (-1715 2755);
FORCEPROP 1 LAST MATERIAL X6S
J 0
(-1675 2775);
DISPLAY 0.489362 (-1675 2775);
PAINT SKYBLUE (-1675 2775);
FORCEPROP 1 LAST TOLERANCE 20%
J 0
(-1675 2825);
DISPLAY 0.489362 (-1675 2825);
PAINT SKYBLUE (-1675 2825);
FORCEPROP 1 LAST VALUE 22UF
J 0
(-1675 2925);
DISPLAY 0.489362 (-1675 2925);
PAINT SKYBLUE (-1675 2925);
FORCEPROP 1 LAST VOLTAGE 4V
J 0
(-1675 2875);
DISPLAY 0.489362 (-1675 2875);
PAINT SKYBLUE (-1675 2875);
FORCEPROP 1 LAST PACK_TYPE C0402
J 0
(-1675 2675);
DISPLAY 0.489362 (-1675 2675);
PAINT SKYBLUE (-1675 2675);
FORCEPROP 2 LAST CDS_LIB pure_quanta
J 0
(-1725 2875);
PAINT MONO (-1725 2875);
DISPLAY INVISIBLE (-1725 2875);
FORCEPROP 1 LAST PATH I80
J 0
(-1675 3025);
DISPLAY 0.978723 (-1675 3025);
PAINT WHITE (-1675 3025);
DISPLAY INVISIBLE (-1675 3025);
FORCEPROP 1 LAST PART_NUMBER CH622KMEB02
J 0
(-1675 2725);
DISPLAY 0.489362 (-1675 2725);
PAINT SKYBLUE (-1675 2725);
DISPLAY INVISIBLE (-1675 2725);
FORCEADD Q_CAP..1
(-1275 2875);
FORCEPROP 1 LAST LOCATION C2246
J 0
(-1225 2975);
DISPLAY 0.489362 (-1225 2975);
PAINT SKYBLUE (-1225 2975);
FORCEPROP 2 LAST $SEC 1
J 0
(-1225 3075);
DISPLAY 0.680851 (-1225 3075);
PAINT MONO (-1225 3075);
DISPLAY INVISIBLE (-1225 3075);
FORCEPROP 2 LAST CDS_SEC 1
J 0
(-1225 3075);
DISPLAY 1.021277 (-1225 3075);
DISPLAY INVISIBLE (-1225 3075);
FORCEPROP 1 LASTPIN (-1275 2975) $PN 1
J 0
(-1265 2955);
DISPLAY 0.489362 (-1265 2955);
FORCEPROP 1 LASTPIN (-1275 2775) $PN 2
J 0
(-1265 2755);
DISPLAY 0.489362 (-1265 2755);
FORCEPROP 1 LAST MATERIAL X6S
J 0
(-1225 2775);
DISPLAY 0.489362 (-1225 2775);
PAINT SKYBLUE (-1225 2775);
FORCEPROP 1 LAST TOLERANCE 20%
J 0
(-1225 2825);
DISPLAY 0.489362 (-1225 2825);
PAINT SKYBLUE (-1225 2825);
FORCEPROP 1 LAST VALUE 22UF
J 0
(-1225 2925);
DISPLAY 0.489362 (-1225 2925);
PAINT SKYBLUE (-1225 2925);
FORCEPROP 1 LAST VOLTAGE 4V
J 0
(-1225 2875);
DISPLAY 0.489362 (-1225 2875);
PAINT SKYBLUE (-1225 2875);
FORCEPROP 1 LAST PACK_TYPE C0402
J 0
(-1225 2675);
DISPLAY 0.489362 (-1225 2675);
PAINT SKYBLUE (-1225 2675);
FORCEPROP 2 LAST CDS_LIB pure_quanta
J 0
(-1275 2875);
PAINT MONO (-1275 2875);
DISPLAY INVISIBLE (-1275 2875);
FORCEPROP 1 LAST PATH I81
J 0
(-1225 3025);
DISPLAY 0.978723 (-1225 3025);
PAINT WHITE (-1225 3025);
DISPLAY INVISIBLE (-1225 3025);
FORCEPROP 1 LAST PART_NUMBER CH622KMEB02
J 0
(-1225 2725);
DISPLAY 0.489362 (-1225 2725);
PAINT SKYBLUE (-1225 2725);
DISPLAY INVISIBLE (-1225 2725);
FORCEADD Q_CAP..1
(-1725 3675);
FORCEPROP 1 LAST LOCATION C2239
J 0
(-1675 3775);
DISPLAY 0.489362 (-1675 3775);
PAINT SKYBLUE (-1675 3775);
FORCEPROP 2 LAST $SEC 1
J 0
(-1675 3875);
DISPLAY 0.680851 (-1675 3875);
PAINT MONO (-1675 3875);
DISPLAY INVISIBLE (-1675 3875);
FORCEPROP 2 LAST CDS_SEC 1
J 0
(-1675 3875);
DISPLAY 1.021277 (-1675 3875);
DISPLAY INVISIBLE (-1675 3875);
FORCEPROP 1 LASTPIN (-1725 3775) $PN 1
J 0
(-1715 3755);
DISPLAY 0.489362 (-1715 3755);
FORCEPROP 1 LASTPIN (-1725 3575) $PN 2
J 0
(-1715 3555);
DISPLAY 0.489362 (-1715 3555);
FORCEPROP 1 LAST MATERIAL X6S
J 0
(-1675 3575);
DISPLAY 0.489362 (-1675 3575);
PAINT SKYBLUE (-1675 3575);
FORCEPROP 1 LAST TOLERANCE 20%
J 0
(-1675 3625);
DISPLAY 0.489362 (-1675 3625);
PAINT SKYBLUE (-1675 3625);
FORCEPROP 1 LAST VALUE 22UF
J 0
(-1675 3725);
DISPLAY 0.489362 (-1675 3725);
PAINT SKYBLUE (-1675 3725);
FORCEPROP 1 LAST VOLTAGE 4V
J 0
(-1675 3675);
DISPLAY 0.489362 (-1675 3675);
PAINT SKYBLUE (-1675 3675);
FORCEPROP 1 LAST PACK_TYPE C0402
J 0
(-1675 3475);
DISPLAY 0.489362 (-1675 3475);
PAINT SKYBLUE (-1675 3475);
FORCEPROP 2 LAST CDS_LIB pure_quanta
J 0
(-1725 3675);
PAINT MONO (-1725 3675);
DISPLAY INVISIBLE (-1725 3675);
FORCEPROP 1 LAST PATH I82
J 0
(-1675 3825);
DISPLAY 0.978723 (-1675 3825);
PAINT WHITE (-1675 3825);
DISPLAY INVISIBLE (-1675 3825);
FORCEPROP 1 LAST PART_NUMBER CH622KMEB02
J 0
(-1675 3525);
DISPLAY 0.489362 (-1675 3525);
PAINT SKYBLUE (-1675 3525);
DISPLAY INVISIBLE (-1675 3525);
FORCEADD Q_CAP..1
(-1275 3675);
FORCEPROP 1 LAST LOCATION C2245
J 0
(-1225 3775);
DISPLAY 0.489362 (-1225 3775);
PAINT SKYBLUE (-1225 3775);
FORCEPROP 2 LAST $SEC 1
J 0
(-1225 3875);
DISPLAY 0.680851 (-1225 3875);
PAINT MONO (-1225 3875);
DISPLAY INVISIBLE (-1225 3875);
FORCEPROP 2 LAST CDS_SEC 1
J 0
(-1225 3875);
DISPLAY 1.021277 (-1225 3875);
DISPLAY INVISIBLE (-1225 3875);
FORCEPROP 1 LASTPIN (-1275 3775) $PN 1
J 0
(-1265 3755);
DISPLAY 0.489362 (-1265 3755);
FORCEPROP 1 LASTPIN (-1275 3575) $PN 2
J 0
(-1265 3555);
DISPLAY 0.489362 (-1265 3555);
FORCEPROP 1 LAST MATERIAL X6S
J 0
(-1225 3575);
DISPLAY 0.489362 (-1225 3575);
PAINT SKYBLUE (-1225 3575);
FORCEPROP 1 LAST TOLERANCE 20%
J 0
(-1225 3625);
DISPLAY 0.489362 (-1225 3625);
PAINT SKYBLUE (-1225 3625);
FORCEPROP 1 LAST VALUE 22UF
J 0
(-1225 3725);
DISPLAY 0.489362 (-1225 3725);
PAINT SKYBLUE (-1225 3725);
FORCEPROP 1 LAST VOLTAGE 4V
J 0
(-1225 3675);
DISPLAY 0.489362 (-1225 3675);
PAINT SKYBLUE (-1225 3675);
FORCEPROP 1 LAST PACK_TYPE C0402
J 0
(-1225 3475);
DISPLAY 0.489362 (-1225 3475);
PAINT SKYBLUE (-1225 3475);
FORCEPROP 2 LAST CDS_LIB pure_quanta
J 0
(-1275 3675);
PAINT MONO (-1275 3675);
DISPLAY INVISIBLE (-1275 3675);
FORCEPROP 1 LAST PATH I83
J 0
(-1225 3825);
DISPLAY 0.978723 (-1225 3825);
PAINT WHITE (-1225 3825);
DISPLAY INVISIBLE (-1225 3825);
FORCEPROP 1 LAST PART_NUMBER CH622KMEB02
J 0
(-1225 3525);
DISPLAY 0.489362 (-1225 3525);
PAINT SKYBLUE (-1225 3525);
DISPLAY INVISIBLE (-1225 3525);
FORCEADD Q_CAP..1
(-825 2875);
FORCEPROP 1 LAST LOCATION C2251
J 0
(-775 2975);
DISPLAY 0.489362 (-775 2975);
PAINT SKYBLUE (-775 2975);
FORCEPROP 2 LAST $SEC 1
J 0
(-775 3075);
DISPLAY 0.680851 (-775 3075);
PAINT MONO (-775 3075);
DISPLAY INVISIBLE (-775 3075);
FORCEPROP 2 LAST CDS_SEC 1
J 0
(-775 3075);
DISPLAY 1.021277 (-775 3075);
DISPLAY INVISIBLE (-775 3075);
FORCEPROP 1 LASTPIN (-825 2975) $PN 1
J 0
(-815 2955);
DISPLAY 0.489362 (-815 2955);
FORCEPROP 1 LASTPIN (-825 2775) $PN 2
J 0
(-815 2755);
DISPLAY 0.489362 (-815 2755);
FORCEPROP 1 LAST MATERIAL X6S
J 0
(-775 2775);
DISPLAY 0.489362 (-775 2775);
PAINT SKYBLUE (-775 2775);
FORCEPROP 1 LAST TOLERANCE 20%
J 0
(-775 2825);
DISPLAY 0.489362 (-775 2825);
PAINT SKYBLUE (-775 2825);
FORCEPROP 1 LAST VALUE 22UF
J 0
(-775 2925);
DISPLAY 0.489362 (-775 2925);
PAINT SKYBLUE (-775 2925);
FORCEPROP 1 LAST VOLTAGE 4V
J 0
(-775 2875);
DISPLAY 0.489362 (-775 2875);
PAINT SKYBLUE (-775 2875);
FORCEPROP 1 LAST PACK_TYPE C0402
J 0
(-775 2675);
DISPLAY 0.489362 (-775 2675);
PAINT SKYBLUE (-775 2675);
FORCEPROP 2 LAST CDS_LIB pure_quanta
J 0
(-825 2875);
PAINT MONO (-825 2875);
DISPLAY INVISIBLE (-825 2875);
FORCEPROP 1 LAST PATH I84
J 0
(-775 3025);
DISPLAY 0.978723 (-775 3025);
PAINT WHITE (-775 3025);
DISPLAY INVISIBLE (-775 3025);
FORCEPROP 1 LAST PART_NUMBER CH622KMEB02
J 0
(-775 2725);
DISPLAY 0.489362 (-775 2725);
PAINT SKYBLUE (-775 2725);
DISPLAY INVISIBLE (-775 2725);
FORCEADD UNIVERSAL_GND..1
(-425 2500);
FORCEPROP 3 LASTPIN (-425 2550) SIG_NAME GND\g
J 0
(-415 2560);
DISPLAY 0.659574 (-415 2560);
PAINT MONO (-415 2560);
DISPLAY INVISIBLE (-415 2560);
FORCEPROP 2 LAST CDS_LIB pure_quanta_power
J 0
(-425 2500);
PAINT MONO (-425 2500);
DISPLAY INVISIBLE (-425 2500);
FORCEPROP 1 LAST HDL_POWER GND
J 1
(-400 2425);
DISPLAY 0.872340 (-400 2425);
PAINT GREEN (-400 2425);
DISPLAY INVISIBLE (-400 2425);
FORCEPROP 1 LAST PATH I85
J 0
(-350 2500);
DISPLAY 0.872340 (-350 2500);
PAINT AQUA (-350 2500);
DISPLAY INVISIBLE (-350 2500);
FORCEADD Q_CAP..1
(-425 2875);
FORCEPROP 1 LAST LOCATION C2256
J 0
(-375 2975);
DISPLAY 0.489362 (-375 2975);
PAINT SKYBLUE (-375 2975);
FORCEPROP 2 LAST $SEC 1
J 0
(-375 3075);
DISPLAY 0.680851 (-375 3075);
PAINT MONO (-375 3075);
DISPLAY INVISIBLE (-375 3075);
FORCEPROP 2 LAST CDS_SEC 1
J 0
(-375 3075);
DISPLAY 1.021277 (-375 3075);
DISPLAY INVISIBLE (-375 3075);
FORCEPROP 1 LASTPIN (-425 2975) $PN 1
J 0
(-415 2955);
DISPLAY 0.489362 (-415 2955);
FORCEPROP 1 LASTPIN (-425 2775) $PN 2
J 0
(-415 2755);
DISPLAY 0.489362 (-415 2755);
FORCEPROP 1 LAST MATERIAL X6S
J 0
(-375 2775);
DISPLAY 0.489362 (-375 2775);
PAINT SKYBLUE (-375 2775);
FORCEPROP 1 LAST TOLERANCE 20%
J 0
(-375 2825);
DISPLAY 0.489362 (-375 2825);
PAINT SKYBLUE (-375 2825);
FORCEPROP 1 LAST VALUE 22UF
J 0
(-375 2925);
DISPLAY 0.489362 (-375 2925);
PAINT SKYBLUE (-375 2925);
FORCEPROP 1 LAST VOLTAGE 4V
J 0
(-375 2875);
DISPLAY 0.489362 (-375 2875);
PAINT SKYBLUE (-375 2875);
FORCEPROP 1 LAST PACK_TYPE C0402
J 0
(-375 2675);
DISPLAY 0.489362 (-375 2675);
PAINT SKYBLUE (-375 2675);
FORCEPROP 2 LAST CDS_LIB pure_quanta
J 0
(-425 2875);
PAINT MONO (-425 2875);
DISPLAY INVISIBLE (-425 2875);
FORCEPROP 1 LAST PATH I86
J 0
(-375 3025);
DISPLAY 0.978723 (-375 3025);
PAINT WHITE (-375 3025);
DISPLAY INVISIBLE (-375 3025);
FORCEPROP 1 LAST PART_NUMBER CH622KMEB02
J 0
(-375 2725);
DISPLAY 0.489362 (-375 2725);
PAINT SKYBLUE (-375 2725);
DISPLAY INVISIBLE (-375 2725);
FORCEADD Q_CAP..1
(-825 3675);
FORCEPROP 1 LAST LOCATION C2250
J 0
(-775 3775);
DISPLAY 0.489362 (-775 3775);
PAINT SKYBLUE (-775 3775);
FORCEPROP 2 LAST $SEC 1
J 0
(-775 3875);
DISPLAY 0.680851 (-775 3875);
PAINT MONO (-775 3875);
DISPLAY INVISIBLE (-775 3875);
FORCEPROP 2 LAST CDS_SEC 1
J 0
(-775 3875);
DISPLAY 1.021277 (-775 3875);
DISPLAY INVISIBLE (-775 3875);
FORCEPROP 1 LASTPIN (-825 3775) $PN 1
J 0
(-815 3755);
DISPLAY 0.489362 (-815 3755);
FORCEPROP 1 LASTPIN (-825 3575) $PN 2
J 0
(-815 3555);
DISPLAY 0.489362 (-815 3555);
FORCEPROP 1 LAST MATERIAL X6S
J 0
(-775 3575);
DISPLAY 0.489362 (-775 3575);
PAINT SKYBLUE (-775 3575);
FORCEPROP 1 LAST TOLERANCE 20%
J 0
(-775 3625);
DISPLAY 0.489362 (-775 3625);
PAINT SKYBLUE (-775 3625);
FORCEPROP 1 LAST VALUE 22UF
J 0
(-775 3725);
DISPLAY 0.489362 (-775 3725);
PAINT SKYBLUE (-775 3725);
FORCEPROP 1 LAST VOLTAGE 4V
J 0
(-775 3675);
DISPLAY 0.489362 (-775 3675);
PAINT SKYBLUE (-775 3675);
FORCEPROP 1 LAST PACK_TYPE C0402
J 0
(-775 3475);
DISPLAY 0.489362 (-775 3475);
PAINT SKYBLUE (-775 3475);
FORCEPROP 2 LAST CDS_LIB pure_quanta
J 0
(-825 3675);
PAINT MONO (-825 3675);
DISPLAY INVISIBLE (-825 3675);
FORCEPROP 1 LAST PATH I87
J 0
(-775 3825);
DISPLAY 0.978723 (-775 3825);
PAINT WHITE (-775 3825);
DISPLAY INVISIBLE (-775 3825);
FORCEPROP 1 LAST PART_NUMBER CH622KMEB02
J 0
(-775 3525);
DISPLAY 0.489362 (-775 3525);
PAINT SKYBLUE (-775 3525);
DISPLAY INVISIBLE (-775 3525);
FORCEADD UNIVERSAL_GND..1
(-425 3300);
FORCEPROP 3 LASTPIN (-425 3350) SIG_NAME GND\g
J 0
(-415 3360);
DISPLAY 0.659574 (-415 3360);
PAINT MONO (-415 3360);
DISPLAY INVISIBLE (-415 3360);
FORCEPROP 2 LAST CDS_LIB pure_quanta_power
J 0
(-425 3300);
PAINT MONO (-425 3300);
DISPLAY INVISIBLE (-425 3300);
FORCEPROP 1 LAST HDL_POWER GND
J 1
(-400 3225);
DISPLAY 0.872340 (-400 3225);
PAINT GREEN (-400 3225);
DISPLAY INVISIBLE (-400 3225);
FORCEPROP 1 LAST PATH I88
J 0
(-350 3300);
DISPLAY 0.872340 (-350 3300);
PAINT AQUA (-350 3300);
DISPLAY INVISIBLE (-350 3300);
FORCEADD Q_CAP..1
(-425 3675);
FORCEPROP 1 LAST LOCATION C2255
J 0
(-375 3775);
DISPLAY 0.489362 (-375 3775);
PAINT SKYBLUE (-375 3775);
FORCEPROP 2 LAST $SEC 1
J 0
(-375 3875);
DISPLAY 0.680851 (-375 3875);
PAINT MONO (-375 3875);
DISPLAY INVISIBLE (-375 3875);
FORCEPROP 2 LAST CDS_SEC 1
J 0
(-375 3875);
DISPLAY 1.021277 (-375 3875);
DISPLAY INVISIBLE (-375 3875);
FORCEPROP 1 LASTPIN (-425 3775) $PN 1
J 0
(-415 3755);
DISPLAY 0.489362 (-415 3755);
FORCEPROP 1 LASTPIN (-425 3575) $PN 2
J 0
(-415 3555);
DISPLAY 0.489362 (-415 3555);
FORCEPROP 1 LAST MATERIAL X6S
J 0
(-375 3575);
DISPLAY 0.489362 (-375 3575);
PAINT SKYBLUE (-375 3575);
FORCEPROP 1 LAST TOLERANCE 20%
J 0
(-375 3625);
DISPLAY 0.489362 (-375 3625);
PAINT SKYBLUE (-375 3625);
FORCEPROP 1 LAST VALUE 22UF
J 0
(-375 3725);
DISPLAY 0.489362 (-375 3725);
PAINT SKYBLUE (-375 3725);
FORCEPROP 1 LAST VOLTAGE 4V
J 0
(-375 3675);
DISPLAY 0.489362 (-375 3675);
PAINT SKYBLUE (-375 3675);
FORCEPROP 1 LAST PACK_TYPE C0402
J 0
(-375 3475);
DISPLAY 0.489362 (-375 3475);
PAINT SKYBLUE (-375 3475);
FORCEPROP 2 LAST CDS_LIB pure_quanta
J 0
(-425 3675);
PAINT MONO (-425 3675);
DISPLAY INVISIBLE (-425 3675);
FORCEPROP 1 LAST PATH I89
J 0
(-375 3825);
DISPLAY 0.978723 (-375 3825);
PAINT WHITE (-375 3825);
DISPLAY INVISIBLE (-375 3825);
FORCEPROP 1 LAST PART_NUMBER CH622KMEB02
J 0
(-375 3525);
DISPLAY 0.489362 (-375 3525);
PAINT SKYBLUE (-375 3525);
DISPLAY INVISIBLE (-375 3525);
FORCEADD Q_CAP..1
(-8550 3675);
FORCEPROP 1 LAST LOCATION C2169
J 0
(-8500 3775);
DISPLAY 0.489362 (-8500 3775);
PAINT SKYBLUE (-8500 3775);
FORCEPROP 2 LAST $SEC 1
J 0
(-8500 3875);
DISPLAY 0.680851 (-8500 3875);
PAINT MONO (-8500 3875);
DISPLAY INVISIBLE (-8500 3875);
FORCEPROP 2 LAST CDS_SEC 1
J 0
(-8500 3875);
DISPLAY 1.021277 (-8500 3875);
DISPLAY INVISIBLE (-8500 3875);
FORCEPROP 1 LASTPIN (-8550 3775) $PN 1
J 0
(-8540 3755);
DISPLAY 0.489362 (-8540 3755);
FORCEPROP 1 LASTPIN (-8550 3575) $PN 2
J 0
(-8540 3555);
DISPLAY 0.489362 (-8540 3555);
FORCEPROP 1 LAST MATERIAL X6S
J 0
(-8500 3575);
DISPLAY 0.489362 (-8500 3575);
PAINT SKYBLUE (-8500 3575);
FORCEPROP 1 LAST TOLERANCE 20%
J 0
(-8500 3625);
DISPLAY 0.489362 (-8500 3625);
PAINT SKYBLUE (-8500 3625);
FORCEPROP 1 LAST VALUE 22UF
J 0
(-8500 3725);
DISPLAY 0.489362 (-8500 3725);
PAINT SKYBLUE (-8500 3725);
FORCEPROP 1 LAST VOLTAGE 4V
J 0
(-8500 3675);
DISPLAY 0.489362 (-8500 3675);
PAINT SKYBLUE (-8500 3675);
FORCEPROP 1 LAST PACK_TYPE C0402
J 0
(-8500 3475);
DISPLAY 0.489362 (-8500 3475);
PAINT SKYBLUE (-8500 3475);
FORCEPROP 2 LAST CDS_LIB pure_quanta
J 0
(-8550 3675);
PAINT MONO (-8550 3675);
DISPLAY INVISIBLE (-8550 3675);
FORCEPROP 1 LAST PATH I9
J 0
(-8500 3825);
DISPLAY 0.978723 (-8500 3825);
PAINT WHITE (-8500 3825);
DISPLAY INVISIBLE (-8500 3825);
FORCEPROP 1 LAST PART_NUMBER CH622KMEB02
J 0
(-8500 3525);
DISPLAY 0.489362 (-8500 3525);
PAINT SKYBLUE (-8500 3525);
DISPLAY INVISIBLE (-8500 3525);
FORCEADD UNIVERSAL_GND..1
(-425 4100);
FORCEPROP 3 LASTPIN (-425 4150) SIG_NAME GND\g
J 0
(-415 4160);
DISPLAY 0.659574 (-415 4160);
PAINT MONO (-415 4160);
DISPLAY INVISIBLE (-415 4160);
FORCEPROP 2 LAST CDS_LIB pure_quanta_power
J 0
(-425 4100);
PAINT MONO (-425 4100);
DISPLAY INVISIBLE (-425 4100);
FORCEPROP 1 LAST HDL_POWER GND
J 1
(-400 4025);
DISPLAY 0.872340 (-400 4025);
PAINT GREEN (-400 4025);
DISPLAY INVISIBLE (-400 4025);
FORCEPROP 1 LAST PATH I90
J 0
(-350 4100);
DISPLAY 0.872340 (-350 4100);
PAINT AQUA (-350 4100);
DISPLAY INVISIBLE (-350 4100);
FORCEADD Q_CAP..1
(-3975 4475);
FORCEPROP 1 LAST LOCATION C2208
J 0
(-3925 4575);
DISPLAY 0.489362 (-3925 4575);
PAINT SKYBLUE (-3925 4575);
FORCEPROP 2 LAST $SEC 1
J 0
(-3925 4675);
DISPLAY 0.680851 (-3925 4675);
PAINT MONO (-3925 4675);
DISPLAY INVISIBLE (-3925 4675);
FORCEPROP 2 LAST CDS_SEC 1
J 0
(-3925 4675);
DISPLAY 1.021277 (-3925 4675);
DISPLAY INVISIBLE (-3925 4675);
FORCEPROP 1 LASTPIN (-3975 4575) $PN 1
J 0
(-3965 4555);
DISPLAY 0.489362 (-3965 4555);
FORCEPROP 1 LASTPIN (-3975 4375) $PN 2
J 0
(-3965 4355);
DISPLAY 0.489362 (-3965 4355);
FORCEPROP 1 LAST MATERIAL X6S
J 0
(-3925 4375);
DISPLAY 0.489362 (-3925 4375);
PAINT SKYBLUE (-3925 4375);
FORCEPROP 1 LAST TOLERANCE 20%
J 0
(-3925 4425);
DISPLAY 0.489362 (-3925 4425);
PAINT SKYBLUE (-3925 4425);
FORCEPROP 1 LAST VALUE 22UF
J 0
(-3925 4525);
DISPLAY 0.489362 (-3925 4525);
PAINT SKYBLUE (-3925 4525);
FORCEPROP 1 LAST VOLTAGE 4V
J 0
(-3925 4475);
DISPLAY 0.489362 (-3925 4475);
PAINT SKYBLUE (-3925 4475);
FORCEPROP 1 LAST PACK_TYPE C0402
J 0
(-3925 4275);
DISPLAY 0.489362 (-3925 4275);
PAINT SKYBLUE (-3925 4275);
FORCEPROP 2 LAST CDS_LIB pure_quanta
J 0
(-3975 4475);
PAINT MONO (-3975 4475);
DISPLAY INVISIBLE (-3975 4475);
FORCEPROP 1 LAST PATH I91
J 0
(-3925 4625);
DISPLAY 0.978723 (-3925 4625);
PAINT WHITE (-3925 4625);
DISPLAY INVISIBLE (-3925 4625);
FORCEPROP 1 LAST PART_NUMBER CH622KMEB02
J 0
(-3925 4325);
DISPLAY 0.489362 (-3925 4325);
PAINT SKYBLUE (-3925 4325);
DISPLAY INVISIBLE (-3925 4325);
FORCEADD Q_CAP..1
(-3525 4475);
FORCEPROP 1 LAST LOCATION C2214
J 0
(-3475 4575);
DISPLAY 0.489362 (-3475 4575);
PAINT SKYBLUE (-3475 4575);
FORCEPROP 2 LAST $SEC 1
J 0
(-3475 4675);
DISPLAY 0.680851 (-3475 4675);
PAINT MONO (-3475 4675);
DISPLAY INVISIBLE (-3475 4675);
FORCEPROP 2 LAST CDS_SEC 1
J 0
(-3475 4675);
DISPLAY 1.021277 (-3475 4675);
DISPLAY INVISIBLE (-3475 4675);
FORCEPROP 1 LASTPIN (-3525 4575) $PN 1
J 0
(-3515 4555);
DISPLAY 0.489362 (-3515 4555);
FORCEPROP 1 LASTPIN (-3525 4375) $PN 2
J 0
(-3515 4355);
DISPLAY 0.489362 (-3515 4355);
FORCEPROP 1 LAST MATERIAL X6S
J 0
(-3475 4375);
DISPLAY 0.489362 (-3475 4375);
PAINT SKYBLUE (-3475 4375);
FORCEPROP 1 LAST TOLERANCE 20%
J 0
(-3475 4425);
DISPLAY 0.489362 (-3475 4425);
PAINT SKYBLUE (-3475 4425);
FORCEPROP 1 LAST VALUE 22UF
J 0
(-3475 4525);
DISPLAY 0.489362 (-3475 4525);
PAINT SKYBLUE (-3475 4525);
FORCEPROP 1 LAST VOLTAGE 4V
J 0
(-3475 4475);
DISPLAY 0.489362 (-3475 4475);
PAINT SKYBLUE (-3475 4475);
FORCEPROP 1 LAST PACK_TYPE C0402
J 0
(-3475 4275);
DISPLAY 0.489362 (-3475 4275);
PAINT SKYBLUE (-3475 4275);
FORCEPROP 2 LAST CDS_LIB pure_quanta
J 0
(-3525 4475);
PAINT MONO (-3525 4475);
DISPLAY INVISIBLE (-3525 4475);
FORCEPROP 1 LAST PATH I92
J 0
(-3475 4625);
DISPLAY 0.978723 (-3475 4625);
PAINT WHITE (-3475 4625);
DISPLAY INVISIBLE (-3475 4625);
FORCEPROP 1 LAST PART_NUMBER CH622KMEB02
J 0
(-3475 4325);
DISPLAY 0.489362 (-3475 4325);
PAINT SKYBLUE (-3475 4325);
DISPLAY INVISIBLE (-3475 4325);
FORCEADD Q_CAP..1
(-3975 5250);
FORCEPROP 1 LAST LOCATION C2207
J 0
(-3925 5350);
DISPLAY 0.489362 (-3925 5350);
PAINT SKYBLUE (-3925 5350);
FORCEPROP 2 LAST $SEC 1
J 0
(-3925 5450);
DISPLAY 0.680851 (-3925 5450);
PAINT MONO (-3925 5450);
DISPLAY INVISIBLE (-3925 5450);
FORCEPROP 2 LAST CDS_SEC 1
J 0
(-3925 5450);
DISPLAY 1.021277 (-3925 5450);
DISPLAY INVISIBLE (-3925 5450);
FORCEPROP 1 LASTPIN (-3975 5350) $PN 1
J 0
(-3965 5330);
DISPLAY 0.489362 (-3965 5330);
FORCEPROP 1 LASTPIN (-3975 5150) $PN 2
J 0
(-3965 5130);
DISPLAY 0.489362 (-3965 5130);
FORCEPROP 1 LAST MATERIAL X6S
J 0
(-3925 5150);
DISPLAY 0.489362 (-3925 5150);
PAINT SKYBLUE (-3925 5150);
FORCEPROP 1 LAST TOLERANCE 20%
J 0
(-3925 5200);
DISPLAY 0.489362 (-3925 5200);
PAINT SKYBLUE (-3925 5200);
FORCEPROP 1 LAST VALUE 22UF
J 0
(-3925 5300);
DISPLAY 0.489362 (-3925 5300);
PAINT SKYBLUE (-3925 5300);
FORCEPROP 1 LAST VOLTAGE 4V
J 0
(-3925 5250);
DISPLAY 0.489362 (-3925 5250);
PAINT SKYBLUE (-3925 5250);
FORCEPROP 1 LAST PACK_TYPE C0402
J 0
(-3925 5050);
DISPLAY 0.489362 (-3925 5050);
PAINT SKYBLUE (-3925 5050);
FORCEPROP 2 LAST CDS_LIB pure_quanta
J 0
(-3975 5250);
PAINT MONO (-3975 5250);
DISPLAY INVISIBLE (-3975 5250);
FORCEPROP 1 LAST PATH I93
J 0
(-3925 5400);
DISPLAY 0.978723 (-3925 5400);
PAINT WHITE (-3925 5400);
DISPLAY INVISIBLE (-3925 5400);
FORCEPROP 1 LAST PART_NUMBER CH622KMEB02
J 0
(-3925 5100);
DISPLAY 0.489362 (-3925 5100);
PAINT SKYBLUE (-3925 5100);
DISPLAY INVISIBLE (-3925 5100);
FORCEADD Q_CAP..1
(-3525 5250);
FORCEPROP 1 LAST LOCATION C2213
J 0
(-3475 5350);
DISPLAY 0.489362 (-3475 5350);
PAINT SKYBLUE (-3475 5350);
FORCEPROP 2 LAST $SEC 1
J 0
(-3475 5450);
DISPLAY 0.680851 (-3475 5450);
PAINT MONO (-3475 5450);
DISPLAY INVISIBLE (-3475 5450);
FORCEPROP 2 LAST CDS_SEC 1
J 0
(-3475 5450);
DISPLAY 1.021277 (-3475 5450);
DISPLAY INVISIBLE (-3475 5450);
FORCEPROP 1 LASTPIN (-3525 5350) $PN 1
J 0
(-3515 5330);
DISPLAY 0.489362 (-3515 5330);
FORCEPROP 1 LASTPIN (-3525 5150) $PN 2
J 0
(-3515 5130);
DISPLAY 0.489362 (-3515 5130);
FORCEPROP 1 LAST MATERIAL X6S
J 0
(-3475 5150);
DISPLAY 0.489362 (-3475 5150);
PAINT SKYBLUE (-3475 5150);
FORCEPROP 1 LAST TOLERANCE 20%
J 0
(-3475 5200);
DISPLAY 0.489362 (-3475 5200);
PAINT SKYBLUE (-3475 5200);
FORCEPROP 1 LAST VALUE 22UF
J 0
(-3475 5300);
DISPLAY 0.489362 (-3475 5300);
PAINT SKYBLUE (-3475 5300);
FORCEPROP 1 LAST VOLTAGE 4V
J 0
(-3475 5250);
DISPLAY 0.489362 (-3475 5250);
PAINT SKYBLUE (-3475 5250);
FORCEPROP 1 LAST PACK_TYPE C0402
J 0
(-3475 5050);
DISPLAY 0.489362 (-3475 5050);
PAINT SKYBLUE (-3475 5050);
FORCEPROP 2 LAST CDS_LIB pure_quanta
J 0
(-3525 5250);
PAINT MONO (-3525 5250);
DISPLAY INVISIBLE (-3525 5250);
FORCEPROP 1 LAST PATH I94
J 0
(-3475 5400);
DISPLAY 0.978723 (-3475 5400);
PAINT WHITE (-3475 5400);
DISPLAY INVISIBLE (-3475 5400);
FORCEPROP 1 LAST PART_NUMBER CH622KMEB02
J 0
(-3475 5100);
DISPLAY 0.489362 (-3475 5100);
PAINT SKYBLUE (-3475 5100);
DISPLAY INVISIBLE (-3475 5100);
FORCEADD Q_CAP..1
(-3075 4475);
FORCEPROP 1 LAST LOCATION C2220
J 0
(-3025 4575);
DISPLAY 0.489362 (-3025 4575);
PAINT SKYBLUE (-3025 4575);
FORCEPROP 2 LAST $SEC 1
J 0
(-3025 4675);
DISPLAY 0.680851 (-3025 4675);
PAINT MONO (-3025 4675);
DISPLAY INVISIBLE (-3025 4675);
FORCEPROP 2 LAST CDS_SEC 1
J 0
(-3025 4675);
DISPLAY 1.021277 (-3025 4675);
DISPLAY INVISIBLE (-3025 4675);
FORCEPROP 1 LASTPIN (-3075 4575) $PN 1
J 0
(-3065 4555);
DISPLAY 0.489362 (-3065 4555);
FORCEPROP 1 LASTPIN (-3075 4375) $PN 2
J 0
(-3065 4355);
DISPLAY 0.489362 (-3065 4355);
FORCEPROP 1 LAST MATERIAL X6S
J 0
(-3025 4375);
DISPLAY 0.489362 (-3025 4375);
PAINT SKYBLUE (-3025 4375);
FORCEPROP 1 LAST TOLERANCE 20%
J 0
(-3025 4425);
DISPLAY 0.489362 (-3025 4425);
PAINT SKYBLUE (-3025 4425);
FORCEPROP 1 LAST VALUE 22UF
J 0
(-3025 4525);
DISPLAY 0.489362 (-3025 4525);
PAINT SKYBLUE (-3025 4525);
FORCEPROP 1 LAST VOLTAGE 4V
J 0
(-3025 4475);
DISPLAY 0.489362 (-3025 4475);
PAINT SKYBLUE (-3025 4475);
FORCEPROP 1 LAST PACK_TYPE C0402
J 0
(-3025 4275);
DISPLAY 0.489362 (-3025 4275);
PAINT SKYBLUE (-3025 4275);
FORCEPROP 2 LAST CDS_LIB pure_quanta
J 0
(-3075 4475);
PAINT MONO (-3075 4475);
DISPLAY INVISIBLE (-3075 4475);
FORCEPROP 1 LAST PATH I95
J 0
(-3025 4625);
DISPLAY 0.978723 (-3025 4625);
PAINT WHITE (-3025 4625);
DISPLAY INVISIBLE (-3025 4625);
FORCEPROP 1 LAST PART_NUMBER CH622KMEB02
J 0
(-3025 4325);
DISPLAY 0.489362 (-3025 4325);
PAINT SKYBLUE (-3025 4325);
DISPLAY INVISIBLE (-3025 4325);
FORCEADD Q_CAP..1
(-2625 4475);
FORCEPROP 1 LAST LOCATION C2226
J 0
(-2575 4575);
DISPLAY 0.489362 (-2575 4575);
PAINT SKYBLUE (-2575 4575);
FORCEPROP 2 LAST $SEC 1
J 0
(-2575 4675);
DISPLAY 0.680851 (-2575 4675);
PAINT MONO (-2575 4675);
DISPLAY INVISIBLE (-2575 4675);
FORCEPROP 2 LAST CDS_SEC 1
J 0
(-2575 4675);
DISPLAY 1.021277 (-2575 4675);
DISPLAY INVISIBLE (-2575 4675);
FORCEPROP 1 LASTPIN (-2625 4575) $PN 1
J 0
(-2615 4555);
DISPLAY 0.489362 (-2615 4555);
FORCEPROP 1 LASTPIN (-2625 4375) $PN 2
J 0
(-2615 4355);
DISPLAY 0.489362 (-2615 4355);
FORCEPROP 1 LAST MATERIAL X6S
J 0
(-2575 4375);
DISPLAY 0.489362 (-2575 4375);
PAINT SKYBLUE (-2575 4375);
FORCEPROP 1 LAST TOLERANCE 20%
J 0
(-2575 4425);
DISPLAY 0.489362 (-2575 4425);
PAINT SKYBLUE (-2575 4425);
FORCEPROP 1 LAST VALUE 22UF
J 0
(-2575 4525);
DISPLAY 0.489362 (-2575 4525);
PAINT SKYBLUE (-2575 4525);
FORCEPROP 1 LAST VOLTAGE 4V
J 0
(-2575 4475);
DISPLAY 0.489362 (-2575 4475);
PAINT SKYBLUE (-2575 4475);
FORCEPROP 1 LAST PACK_TYPE C0402
J 0
(-2575 4275);
DISPLAY 0.489362 (-2575 4275);
PAINT SKYBLUE (-2575 4275);
FORCEPROP 2 LAST CDS_LIB pure_quanta
J 0
(-2625 4475);
PAINT MONO (-2625 4475);
DISPLAY INVISIBLE (-2625 4475);
FORCEPROP 1 LAST PATH I96
J 0
(-2575 4625);
DISPLAY 0.978723 (-2575 4625);
PAINT WHITE (-2575 4625);
DISPLAY INVISIBLE (-2575 4625);
FORCEPROP 1 LAST PART_NUMBER CH622KMEB02
J 0
(-2575 4325);
DISPLAY 0.489362 (-2575 4325);
PAINT SKYBLUE (-2575 4325);
DISPLAY INVISIBLE (-2575 4325);
FORCEADD Q_CAP..1
(-2175 4475);
FORCEPROP 1 LAST LOCATION C2232
J 0
(-2125 4575);
DISPLAY 0.489362 (-2125 4575);
PAINT SKYBLUE (-2125 4575);
FORCEPROP 2 LAST $SEC 1
J 0
(-2125 4675);
DISPLAY 0.680851 (-2125 4675);
PAINT MONO (-2125 4675);
DISPLAY INVISIBLE (-2125 4675);
FORCEPROP 2 LAST CDS_SEC 1
J 0
(-2125 4675);
DISPLAY 1.021277 (-2125 4675);
DISPLAY INVISIBLE (-2125 4675);
FORCEPROP 1 LASTPIN (-2175 4575) $PN 1
J 0
(-2165 4555);
DISPLAY 0.489362 (-2165 4555);
FORCEPROP 1 LASTPIN (-2175 4375) $PN 2
J 0
(-2165 4355);
DISPLAY 0.489362 (-2165 4355);
FORCEPROP 1 LAST MATERIAL X6S
J 0
(-2125 4375);
DISPLAY 0.489362 (-2125 4375);
PAINT SKYBLUE (-2125 4375);
FORCEPROP 1 LAST TOLERANCE 20%
J 0
(-2125 4425);
DISPLAY 0.489362 (-2125 4425);
PAINT SKYBLUE (-2125 4425);
FORCEPROP 1 LAST VALUE 22UF
J 0
(-2125 4525);
DISPLAY 0.489362 (-2125 4525);
PAINT SKYBLUE (-2125 4525);
FORCEPROP 1 LAST VOLTAGE 4V
J 0
(-2125 4475);
DISPLAY 0.489362 (-2125 4475);
PAINT SKYBLUE (-2125 4475);
FORCEPROP 1 LAST PACK_TYPE C0402
J 0
(-2125 4275);
DISPLAY 0.489362 (-2125 4275);
PAINT SKYBLUE (-2125 4275);
FORCEPROP 2 LAST CDS_LIB pure_quanta
J 0
(-2175 4475);
PAINT MONO (-2175 4475);
DISPLAY INVISIBLE (-2175 4475);
FORCEPROP 1 LAST PATH I97
J 0
(-2125 4625);
DISPLAY 0.978723 (-2125 4625);
PAINT WHITE (-2125 4625);
DISPLAY INVISIBLE (-2125 4625);
FORCEPROP 1 LAST PART_NUMBER CH622KMEB02
J 0
(-2125 4325);
DISPLAY 0.489362 (-2125 4325);
PAINT SKYBLUE (-2125 4325);
DISPLAY INVISIBLE (-2125 4325);
FORCEADD Q_CAP..1
(-3075 5250);
FORCEPROP 1 LAST LOCATION C2219
J 0
(-3025 5350);
DISPLAY 0.489362 (-3025 5350);
PAINT SKYBLUE (-3025 5350);
FORCEPROP 2 LAST $SEC 1
J 0
(-3025 5450);
DISPLAY 0.680851 (-3025 5450);
PAINT MONO (-3025 5450);
DISPLAY INVISIBLE (-3025 5450);
FORCEPROP 2 LAST CDS_SEC 1
J 0
(-3025 5450);
DISPLAY 1.021277 (-3025 5450);
DISPLAY INVISIBLE (-3025 5450);
FORCEPROP 1 LASTPIN (-3075 5350) $PN 1
J 0
(-3065 5330);
DISPLAY 0.489362 (-3065 5330);
FORCEPROP 1 LASTPIN (-3075 5150) $PN 2
J 0
(-3065 5130);
DISPLAY 0.489362 (-3065 5130);
FORCEPROP 1 LAST MATERIAL X6S
J 0
(-3025 5150);
DISPLAY 0.489362 (-3025 5150);
PAINT SKYBLUE (-3025 5150);
FORCEPROP 1 LAST TOLERANCE 20%
J 0
(-3025 5200);
DISPLAY 0.489362 (-3025 5200);
PAINT SKYBLUE (-3025 5200);
FORCEPROP 1 LAST VALUE 22UF
J 0
(-3025 5300);
DISPLAY 0.489362 (-3025 5300);
PAINT SKYBLUE (-3025 5300);
FORCEPROP 1 LAST VOLTAGE 4V
J 0
(-3025 5250);
DISPLAY 0.489362 (-3025 5250);
PAINT SKYBLUE (-3025 5250);
FORCEPROP 1 LAST PACK_TYPE C0402
J 0
(-3025 5050);
DISPLAY 0.489362 (-3025 5050);
PAINT SKYBLUE (-3025 5050);
FORCEPROP 2 LAST CDS_LIB pure_quanta
J 0
(-3075 5250);
PAINT MONO (-3075 5250);
DISPLAY INVISIBLE (-3075 5250);
FORCEPROP 1 LAST PATH I98
J 0
(-3025 5400);
DISPLAY 0.978723 (-3025 5400);
PAINT WHITE (-3025 5400);
DISPLAY INVISIBLE (-3025 5400);
FORCEPROP 1 LAST PART_NUMBER CH622KMEB02
J 0
(-3025 5100);
DISPLAY 0.489362 (-3025 5100);
PAINT SKYBLUE (-3025 5100);
DISPLAY INVISIBLE (-3025 5100);
FORCEADD Q_CAP..1
(-2625 5250);
FORCEPROP 1 LAST LOCATION C2225
J 0
(-2575 5350);
DISPLAY 0.489362 (-2575 5350);
PAINT SKYBLUE (-2575 5350);
FORCEPROP 2 LAST $SEC 1
J 0
(-2575 5450);
DISPLAY 0.680851 (-2575 5450);
PAINT MONO (-2575 5450);
DISPLAY INVISIBLE (-2575 5450);
FORCEPROP 2 LAST CDS_SEC 1
J 0
(-2575 5450);
DISPLAY 1.021277 (-2575 5450);
DISPLAY INVISIBLE (-2575 5450);
FORCEPROP 1 LASTPIN (-2625 5350) $PN 1
J 0
(-2615 5330);
DISPLAY 0.489362 (-2615 5330);
FORCEPROP 1 LASTPIN (-2625 5150) $PN 2
J 0
(-2615 5130);
DISPLAY 0.489362 (-2615 5130);
FORCEPROP 1 LAST MATERIAL X6S
J 0
(-2575 5150);
DISPLAY 0.489362 (-2575 5150);
PAINT SKYBLUE (-2575 5150);
FORCEPROP 1 LAST TOLERANCE 20%
J 0
(-2575 5200);
DISPLAY 0.489362 (-2575 5200);
PAINT SKYBLUE (-2575 5200);
FORCEPROP 1 LAST VALUE 22UF
J 0
(-2575 5300);
DISPLAY 0.489362 (-2575 5300);
PAINT SKYBLUE (-2575 5300);
FORCEPROP 1 LAST VOLTAGE 4V
J 0
(-2575 5250);
DISPLAY 0.489362 (-2575 5250);
PAINT SKYBLUE (-2575 5250);
FORCEPROP 1 LAST PACK_TYPE C0402
J 0
(-2575 5050);
DISPLAY 0.489362 (-2575 5050);
PAINT SKYBLUE (-2575 5050);
FORCEPROP 2 LAST CDS_LIB pure_quanta
J 0
(-2625 5250);
PAINT MONO (-2625 5250);
DISPLAY INVISIBLE (-2625 5250);
FORCEPROP 1 LAST PATH I99
J 0
(-2575 5400);
DISPLAY 0.978723 (-2575 5400);
PAINT WHITE (-2575 5400);
DISPLAY INVISIBLE (-2575 5400);
FORCEPROP 1 LAST PART_NUMBER CH622KMEB02
J 0
(-2575 5100);
DISPLAY 0.489362 (-2575 5100);
PAINT SKYBLUE (-2575 5100);
DISPLAY INVISIBLE (-2575 5100);
FORCEADD QUANTA_TITLE_BLOCK_C..1
(25 -225);
FORCEPROP 0 LAST CDS_CON_LAST_MODIFIED Thu Sep 14 16:12:03 2023
J 0
(-1860 -210);
DISPLAY INVISIBLE (-1860 -210);
FORCEPROP 1 LAST CUSTOM_TXT_CDS <CON_LAST_MODIFIED>
J 0
(-1860 -210);
DISPLAY 0.978723 (-1860 -210);
FORCEPROP 2 LAST CUSTOM_TXT_CDS <XR_PAGE_TITLE>
J 0
(-7865 5025);
DISPLAY 0.638298 (-7865 5025);
PAINT PINK (-7865 5025);
DISPLAY INVISIBLE (-7865 5025);
FORCEPROP 1 LAST CUSTOM_TXT_CDS <NAME_2>
J 0
(-3150 -175);
FORCEPROP 1 LAST CUSTOM_TXT_CDS <NAME_1>
J 0
(-3150 -50);
FORCEPROP 1 LAST CUSTOM_TXT_CDS <Q_NUMBER>
J 0
(-1378 -122);
DISPLAY 1.212766 (-1378 -122);
FORCEPROP 1 LAST CUSTOM_TXT_CDS <Q_PROJ>
J 0
(-2357 -123);
DISPLAY 1.212766 (-2357 -123);
FORCEPROP 1 LAST CUSTOM_TXT_CDS <Q_REV>
J 0
(-159 -122);
DISPLAY 1.212766 (-159 -122);
FORCEPROP 1 LAST CUSTOM_TXT_CDS <CON_PAGE_NUM> OF <CON_TOTAL_PAGES>
J 0
(-421 -207);
DISPLAY 0.978723 (-421 -207);
FORCEPROP 1 LAST Q_TITLE CPU0 CAVITY BOT DECOUPLING CAPS 1/3
J 0
(-9341 -199);
DISPLAY 2.446809 (-9341 -199);
PAINT GREEN (-9341 -199);
FORCEPROP 2 LAST PAGE_BORDER TRUE
J 0
(-7865 5025);
DISPLAY 0.638298 (-7865 5025);
PAINT PINK (-7865 5025);
DISPLAY INVISIBLE (-7865 5025);
FORCEPROP 1 LAST CDS_LMAN_SYM_OUTLINE -9475,6775,100,-125
J 0
(25 -225);
DISPLAY 0.468085 (25 -225);
PAINT GREEN (25 -225);
DISPLAY INVISIBLE (25 -225);
FORCEPROP 2 LAST CDS_LIB pure_quanta
J 0
(25 -225);
DISPLAY INVISIBLE (25 -225);
FORCEPROP 2 LAST CDS_XR_PAGE_TITLE CR-69 : @T6G_MB_LIB.T6G(SCH_1):PAGE69
J 0
(-7865 5025);
DISPLAY 0.638298 (-7865 5025);
PAINT PINK (-7865 5025);
DISPLAY INVISIBLE (-7865 5025);
FORCEPROP 1 LAST Q_DEPT BU9
J 1
(-3738 -176);
DISPLAY 1.957447 (-3738 -176);
PAINT GREEN (-3738 -176);
DISPLAY INVISIBLE (-3738 -176);
FORCEPROP 1 LAST COMMENT_BODY TRUE
J 0
(37 -238);
DISPLAY 0.978723 (37 -238);
PAINT GREEN (37 -238);
DISPLAY INVISIBLE (37 -238);
WIRE 16 -1 (-7650 3050)(-8100 3050);
WIRE 16 -1 (-7200 3050)(-7650 3050);
WIRE 16 -1 (-7650 2975)(-7650 3050);
WIRE 16 -1 (-8100 3050)(-8100 2975);
WIRE 16 -1 (-8100 3050)(-8550 3050);
WIRE 16 -1 (-8550 2975)(-8550 3050);
WIRE 16 -1 (-8550 3050)(-9000 3050);
WIRE 16 -1 (-6750 3050)(-7200 3050);
WIRE 16 -1 (-7200 2975)(-7200 3050);
WIRE 16 -1 (-6300 3050)(-6750 3050);
WIRE 16 -1 (-6750 3050)(-6750 2975);
WIRE 16 -1 (-9000 3050)(-9000 3100);
WIRE 16 -1 (-9000 3050)(-9000 2975);
WIRE 16 -1 (-5850 3050)(-6300 3050);
WIRE 16 -1 (-6300 2975)(-6300 3050);
WIRE 16 -1 (-5400 3050)(-5850 3050);
WIRE 16 -1 (-5850 2975)(-5850 3050);
WIRE 16 -1 (-5000 3050)(-5400 3050);
WIRE 16 -1 (-5400 3050)(-5400 2975);
WIRE 16 -1 (-5000 2975)(-5000 3050);
WIRE 16 -1 (-7650 2250)(-8100 2250);
WIRE 16 -1 (-7200 2250)(-7650 2250);
WIRE 16 -1 (-7650 2175)(-7650 2250);
WIRE 16 -1 (-8100 2250)(-8100 2175);
WIRE 16 -1 (-8100 2250)(-8550 2250);
WIRE 16 -1 (-8550 2175)(-8550 2250);
WIRE 16 -1 (-8550 2250)(-9000 2250);
WIRE 16 -1 (-7200 2175)(-7200 2250);
WIRE 16 -1 (-9000 2250)(-9000 2300);
WIRE 16 -1 (-9000 2250)(-9000 2175);
WIRE 16 -1 (-8100 2650)(-8550 2650);
WIRE 16 -1 (-7650 2650)(-8100 2650);
WIRE 16 -1 (-8100 2650)(-8100 2775);
WIRE 16 -1 (-8550 2650)(-8550 2775);
WIRE 16 -1 (-8550 2650)(-9000 2650);
WIRE 16 -1 (-9000 2650)(-9000 2775);
WIRE 16 -1 (-7200 2650)(-7650 2650);
WIRE 16 -1 (-7650 2650)(-7650 2775);
WIRE 16 -1 (-6750 2650)(-7200 2650);
WIRE 16 -1 (-7200 2650)(-7200 2775);
WIRE 16 -1 (-6300 2650)(-6750 2650);
WIRE 16 -1 (-6750 2650)(-6750 2775);
WIRE 16 -1 (-5850 2650)(-6300 2650);
WIRE 16 -1 (-6300 2650)(-6300 2775);
WIRE 16 -1 (-5400 2650)(-5850 2650);
WIRE 16 -1 (-5850 2650)(-5850 2775);
WIRE 16 -1 (-5400 2650)(-5000 2650);
WIRE 16 -1 (-5400 2650)(-5400 2775);
WIRE 16 -1 (-5000 2650)(-5000 2775);
WIRE 16 -1 (-5000 2550)(-5000 2650);
WIRE 16 -1 (-8100 1850)(-8550 1850);
WIRE 16 -1 (-7650 1850)(-8100 1850);
WIRE 16 -1 (-8100 1850)(-8100 1975);
WIRE 16 -1 (-8550 1850)(-8550 1975);
WIRE 16 -1 (-8550 1850)(-9000 1850);
WIRE 16 -1 (-9000 1850)(-9000 1975);
WIRE 16 -1 (-7200 1850)(-7650 1850);
WIRE 16 -1 (-7650 1850)(-7650 1975);
WIRE 16 -1 (-7200 1850)(-7200 1975);
WIRE 16 -1 (-7200 1725)(-7200 1850);
WIRE 16 -1 (-7650 3850)(-8100 3850);
WIRE 16 -1 (-7200 3850)(-7650 3850);
WIRE 16 -1 (-7650 3775)(-7650 3850);
WIRE 16 -1 (-8100 3850)(-8100 3775);
WIRE 16 -1 (-8100 3850)(-8550 3850);
WIRE 16 -1 (-8550 3775)(-8550 3850);
WIRE 16 -1 (-8550 3850)(-9000 3850);
WIRE 16 -1 (-6750 3850)(-7200 3850);
WIRE 16 -1 (-7200 3775)(-7200 3850);
WIRE 16 -1 (-6300 3850)(-6750 3850);
WIRE 16 -1 (-6750 3850)(-6750 3775);
WIRE 16 -1 (-9000 3850)(-9000 3900);
WIRE 16 -1 (-9000 3850)(-9000 3775);
WIRE 16 -1 (-5850 3850)(-6300 3850);
WIRE 16 -1 (-6300 3775)(-6300 3850);
WIRE 16 -1 (-5400 3850)(-5850 3850);
WIRE 16 -1 (-5850 3775)(-5850 3850);
WIRE 16 -1 (-5000 3850)(-5400 3850);
WIRE 16 -1 (-5400 3850)(-5400 3775);
WIRE 16 -1 (-5000 3775)(-5000 3850);
WIRE 16 -1 (-8100 3450)(-8550 3450);
WIRE 16 -1 (-7650 3450)(-8100 3450);
WIRE 16 -1 (-8100 3450)(-8100 3575);
WIRE 16 -1 (-8550 3450)(-8550 3575);
WIRE 16 -1 (-8550 3450)(-9000 3450);
WIRE 16 -1 (-9000 3450)(-9000 3575);
WIRE 16 -1 (-7200 3450)(-7650 3450);
WIRE 16 -1 (-7650 3450)(-7650 3575);
WIRE 16 -1 (-6750 3450)(-7200 3450);
WIRE 16 -1 (-7200 3450)(-7200 3575);
WIRE 16 -1 (-6300 3450)(-6750 3450);
WIRE 16 -1 (-6750 3450)(-6750 3575);
WIRE 16 -1 (-5850 3450)(-6300 3450);
WIRE 16 -1 (-6300 3450)(-6300 3575);
WIRE 16 -1 (-5400 3450)(-5850 3450);
WIRE 16 -1 (-5850 3450)(-5850 3575);
WIRE 16 -1 (-5400 3450)(-5000 3450);
WIRE 16 -1 (-5400 3450)(-5400 3575);
WIRE 16 -1 (-5000 3450)(-5000 3575);
WIRE 16 -1 (-5000 3350)(-5000 3450);
WIRE 16 -1 (-7650 4650)(-8100 4650);
WIRE 16 -1 (-7200 4650)(-7650 4650);
WIRE 16 -1 (-7650 4575)(-7650 4650);
WIRE 16 -1 (-8100 4650)(-8100 4575);
WIRE 16 -1 (-8100 4650)(-8550 4650);
WIRE 16 -1 (-8550 4575)(-8550 4650);
WIRE 16 -1 (-8550 4650)(-9000 4650);
WIRE 16 -1 (-6750 4650)(-7200 4650);
WIRE 16 -1 (-7200 4575)(-7200 4650);
WIRE 16 -1 (-6300 4650)(-6750 4650);
WIRE 16 -1 (-6750 4650)(-6750 4575);
WIRE 16 -1 (-9000 4650)(-9000 4700);
WIRE 16 -1 (-9000 4650)(-9000 4575);
WIRE 16 -1 (-5850 4650)(-6300 4650);
WIRE 16 -1 (-6300 4575)(-6300 4650);
WIRE 16 -1 (-5400 4650)(-5850 4650);
WIRE 16 -1 (-5850 4575)(-5850 4650);
WIRE 16 -1 (-5000 4650)(-5400 4650);
WIRE 16 -1 (-5400 4650)(-5400 4575);
WIRE 16 -1 (-5000 4575)(-5000 4650);
WIRE 16 -1 (-8100 4250)(-8550 4250);
WIRE 16 -1 (-7650 4250)(-8100 4250);
WIRE 16 -1 (-8100 4250)(-8100 4375);
WIRE 16 -1 (-8550 4250)(-8550 4375);
WIRE 16 -1 (-8550 4250)(-9000 4250);
WIRE 16 -1 (-9000 4250)(-9000 4375);
WIRE 16 -1 (-7200 4250)(-7650 4250);
WIRE 16 -1 (-7650 4250)(-7650 4375);
WIRE 16 -1 (-6750 4250)(-7200 4250);
WIRE 16 -1 (-7200 4250)(-7200 4375);
WIRE 16 -1 (-6300 4250)(-6750 4250);
WIRE 16 -1 (-6750 4250)(-6750 4375);
WIRE 16 -1 (-5850 4250)(-6300 4250);
WIRE 16 -1 (-6300 4250)(-6300 4375);
WIRE 16 -1 (-5400 4250)(-5850 4250);
WIRE 16 -1 (-5850 4250)(-5850 4375);
WIRE 16 -1 (-5400 4250)(-5000 4250);
WIRE 16 -1 (-5400 4250)(-5400 4375);
WIRE 16 -1 (-5000 4250)(-5000 4375);
WIRE 16 -1 (-5000 4150)(-5000 4250);
WIRE 16 -1 (-5000 5025)(-5000 5150);
WIRE 16 -1 (-5000 4925)(-5000 5025);
WIRE 16 -1 (-5000 5025)(-5400 5025);
WIRE 16 -1 (-5400 5025)(-5400 5150);
WIRE 16 -1 (-5400 5025)(-5850 5025);
WIRE 16 -1 (-5850 5025)(-5850 5150);
WIRE 16 -1 (-5850 5025)(-6300 5025);
WIRE 16 -1 (-6300 5025)(-6300 5150);
WIRE 16 -1 (-6300 5025)(-6750 5025);
WIRE 16 -1 (-6750 5025)(-6750 5150);
WIRE 16 -1 (-6750 5025)(-7200 5025);
WIRE 16 -1 (-7200 5025)(-7200 5150);
WIRE 16 -1 (-7200 5025)(-7650 5025);
WIRE 16 -1 (-7650 5025)(-7650 5150);
WIRE 16 -1 (-7650 5025)(-8100 5025);
WIRE 16 -1 (-8100 5025)(-8100 5150);
WIRE 16 -1 (-8100 5025)(-8550 5025);
WIRE 16 -1 (-8550 5025)(-8550 5150);
WIRE 16 -1 (-8550 5025)(-9000 5025);
WIRE 16 -1 (-9000 5025)(-9000 5150);
WIRE 16 -1 (-7650 5425)(-8100 5425);
WIRE 16 -1 (-7200 5425)(-7650 5425);
WIRE 16 -1 (-7650 5350)(-7650 5425);
WIRE 16 -1 (-8100 5425)(-8100 5350);
WIRE 16 -1 (-8100 5425)(-8550 5425);
WIRE 16 -1 (-8550 5350)(-8550 5425);
WIRE 16 -1 (-8550 5425)(-9000 5425);
WIRE 16 -1 (-6750 5425)(-7200 5425);
WIRE 16 -1 (-7200 5350)(-7200 5425);
WIRE 16 -1 (-6300 5425)(-6750 5425);
WIRE 16 -1 (-6750 5425)(-6750 5350);
WIRE 16 -1 (-9000 5425)(-9000 5475);
WIRE 16 -1 (-9000 5425)(-9000 5350);
WIRE 16 -1 (-5850 5425)(-6300 5425);
WIRE 16 -1 (-6300 5350)(-6300 5425);
WIRE 16 -1 (-5400 5425)(-5850 5425);
WIRE 16 -1 (-5850 5350)(-5850 5425);
WIRE 16 -1 (-5000 5425)(-5400 5425);
WIRE 16 -1 (-5400 5425)(-5400 5350);
WIRE 16 -1 (-5000 5350)(-5000 5425);
WIRE 16 3135 (-4700 800)(-4700 6100);
WIRE 16 3135 (-9150 800)(-4700 800);
WIRE 16 3135 (-9150 6100)(-4700 6100);
WIRE 16 3135 (-9150 800)(-9150 6100);
WIRE 16 3135 (-9200 6100)(-9150 6100);
WIRE 16 3135 (-9200 800)(-9150 800);
WIRE 16 -1 (-3075 5425)(-3525 5425);
WIRE 16 -1 (-2625 5425)(-3075 5425);
WIRE 16 -1 (-3075 5350)(-3075 5425);
WIRE 16 -1 (-3525 5425)(-3525 5350);
WIRE 16 -1 (-3525 5425)(-3975 5425);
WIRE 16 -1 (-3975 5350)(-3975 5425);
WIRE 16 -1 (-3975 5425)(-4425 5425);
WIRE 16 -1 (-2175 5425)(-2625 5425);
WIRE 16 -1 (-2625 5350)(-2625 5425);
WIRE 16 -1 (-1725 5425)(-2175 5425);
WIRE 16 -1 (-2175 5425)(-2175 5350);
WIRE 16 -1 (-4425 5425)(-4425 5475);
WIRE 16 -1 (-4425 5425)(-4425 5350);
WIRE 16 -1 (-1275 5425)(-1725 5425);
WIRE 16 -1 (-1725 5350)(-1725 5425);
WIRE 16 -1 (-825 5425)(-1275 5425);
WIRE 16 -1 (-1275 5350)(-1275 5425);
WIRE 16 -1 (-425 5425)(-825 5425);
WIRE 16 -1 (-825 5425)(-825 5350);
WIRE 16 -1 (-425 5350)(-425 5425);
WIRE 16 -1 (-425 5025)(-425 5150);
WIRE 16 -1 (-425 4925)(-425 5025);
WIRE 16 -1 (-425 5025)(-825 5025);
WIRE 16 -1 (-825 5025)(-825 5150);
WIRE 16 -1 (-825 5025)(-1275 5025);
WIRE 16 -1 (-1275 5025)(-1275 5150);
WIRE 16 -1 (-1275 5025)(-1725 5025);
WIRE 16 -1 (-1725 5025)(-1725 5150);
WIRE 16 -1 (-1725 5025)(-2175 5025);
WIRE 16 -1 (-2175 5025)(-2175 5150);
WIRE 16 -1 (-2175 5025)(-2625 5025);
WIRE 16 -1 (-2625 5025)(-2625 5150);
WIRE 16 -1 (-2625 5025)(-3075 5025);
WIRE 16 -1 (-3075 5025)(-3075 5150);
WIRE 16 -1 (-3075 5025)(-3525 5025);
WIRE 16 -1 (-3525 5025)(-3525 5150);
WIRE 16 -1 (-3525 5025)(-3975 5025);
WIRE 16 -1 (-3975 5025)(-3975 5150);
WIRE 16 -1 (-3975 5025)(-4425 5025);
WIRE 16 -1 (-4425 5025)(-4425 5150);
WIRE 16 -1 (-3075 4650)(-3525 4650);
WIRE 16 -1 (-2625 4650)(-3075 4650);
WIRE 16 -1 (-3075 4575)(-3075 4650);
WIRE 16 -1 (-3525 4650)(-3525 4575);
WIRE 16 -1 (-3525 4650)(-3975 4650);
WIRE 16 -1 (-3975 4575)(-3975 4650);
WIRE 16 -1 (-3975 4650)(-4425 4650);
WIRE 16 -1 (-2175 4650)(-2625 4650);
WIRE 16 -1 (-2625 4575)(-2625 4650);
WIRE 16 -1 (-1725 4650)(-2175 4650);
WIRE 16 -1 (-2175 4650)(-2175 4575);
WIRE 16 -1 (-4425 4650)(-4425 4700);
WIRE 16 -1 (-4425 4650)(-4425 4575);
WIRE 16 -1 (-1275 4650)(-1725 4650);
WIRE 16 -1 (-1725 4575)(-1725 4650);
WIRE 16 -1 (-825 4650)(-1275 4650);
WIRE 16 -1 (-1275 4575)(-1275 4650);
WIRE 16 -1 (-425 4650)(-825 4650);
WIRE 16 -1 (-825 4650)(-825 4575);
WIRE 16 -1 (-425 4575)(-425 4650);
WIRE 16 -1 (-3525 4250)(-3975 4250);
WIRE 16 -1 (-3075 4250)(-3525 4250);
WIRE 16 -1 (-3525 4250)(-3525 4375);
WIRE 16 -1 (-3975 4250)(-3975 4375);
WIRE 16 -1 (-3975 4250)(-4425 4250);
WIRE 16 -1 (-4425 4250)(-4425 4375);
WIRE 16 -1 (-2625 4250)(-3075 4250);
WIRE 16 -1 (-3075 4250)(-3075 4375);
WIRE 16 -1 (-2175 4250)(-2625 4250);
WIRE 16 -1 (-2625 4250)(-2625 4375);
WIRE 16 -1 (-1725 4250)(-2175 4250);
WIRE 16 -1 (-2175 4250)(-2175 4375);
WIRE 16 -1 (-1275 4250)(-1725 4250);
WIRE 16 -1 (-1725 4250)(-1725 4375);
WIRE 16 -1 (-825 4250)(-1275 4250);
WIRE 16 -1 (-1275 4250)(-1275 4375);
WIRE 16 -1 (-825 4250)(-425 4250);
WIRE 16 -1 (-825 4250)(-825 4375);
WIRE 16 -1 (-425 4250)(-425 4375);
WIRE 16 -1 (-425 4150)(-425 4250);
WIRE 16 -1 (-3075 3850)(-3525 3850);
WIRE 16 -1 (-2625 3850)(-3075 3850);
WIRE 16 -1 (-3075 3775)(-3075 3850);
WIRE 16 -1 (-3525 3850)(-3525 3775);
WIRE 16 -1 (-3525 3850)(-3975 3850);
WIRE 16 -1 (-3975 3775)(-3975 3850);
WIRE 16 -1 (-3975 3850)(-4425 3850);
WIRE 16 -1 (-2175 3850)(-2625 3850);
WIRE 16 -1 (-2625 3775)(-2625 3850);
WIRE 16 -1 (-1725 3850)(-2175 3850);
WIRE 16 -1 (-2175 3850)(-2175 3775);
WIRE 16 -1 (-4425 3850)(-4425 3900);
WIRE 16 -1 (-4425 3850)(-4425 3775);
WIRE 16 -1 (-1275 3850)(-1725 3850);
WIRE 16 -1 (-1725 3775)(-1725 3850);
WIRE 16 -1 (-825 3850)(-1275 3850);
WIRE 16 -1 (-1275 3775)(-1275 3850);
WIRE 16 -1 (-425 3850)(-825 3850);
WIRE 16 -1 (-825 3850)(-825 3775);
WIRE 16 -1 (-425 3775)(-425 3850);
WIRE 16 -1 (-3525 3450)(-3975 3450);
WIRE 16 -1 (-3075 3450)(-3525 3450);
WIRE 16 -1 (-3525 3450)(-3525 3575);
WIRE 16 -1 (-3975 3450)(-3975 3575);
WIRE 16 -1 (-3975 3450)(-4425 3450);
WIRE 16 -1 (-4425 3450)(-4425 3575);
WIRE 16 -1 (-2625 3450)(-3075 3450);
WIRE 16 -1 (-3075 3450)(-3075 3575);
WIRE 16 -1 (-2175 3450)(-2625 3450);
WIRE 16 -1 (-2625 3450)(-2625 3575);
WIRE 16 -1 (-1725 3450)(-2175 3450);
WIRE 16 -1 (-2175 3450)(-2175 3575);
WIRE 16 -1 (-1275 3450)(-1725 3450);
WIRE 16 -1 (-1725 3450)(-1725 3575);
WIRE 16 -1 (-825 3450)(-1275 3450);
WIRE 16 -1 (-1275 3450)(-1275 3575);
WIRE 16 -1 (-825 3450)(-425 3450);
WIRE 16 -1 (-825 3450)(-825 3575);
WIRE 16 -1 (-425 3450)(-425 3575);
WIRE 16 -1 (-425 3350)(-425 3450);
WIRE 16 -1 (-3075 3050)(-3525 3050);
WIRE 16 -1 (-2625 3050)(-3075 3050);
WIRE 16 -1 (-3075 2975)(-3075 3050);
WIRE 16 -1 (-3525 3050)(-3525 2975);
WIRE 16 -1 (-3525 3050)(-3975 3050);
WIRE 16 -1 (-3975 2975)(-3975 3050);
WIRE 16 -1 (-3975 3050)(-4425 3050);
WIRE 16 -1 (-2175 3050)(-2625 3050);
WIRE 16 -1 (-2625 2975)(-2625 3050);
WIRE 16 -1 (-1725 3050)(-2175 3050);
WIRE 16 -1 (-2175 3050)(-2175 2975);
WIRE 16 -1 (-4425 3050)(-4425 3100);
WIRE 16 -1 (-4425 3050)(-4425 2975);
WIRE 16 -1 (-1275 3050)(-1725 3050);
WIRE 16 -1 (-1725 2975)(-1725 3050);
WIRE 16 -1 (-825 3050)(-1275 3050);
WIRE 16 -1 (-1275 2975)(-1275 3050);
WIRE 16 -1 (-425 3050)(-825 3050);
WIRE 16 -1 (-825 3050)(-825 2975);
WIRE 16 -1 (-425 2975)(-425 3050);
WIRE 16 -1 (-3525 2650)(-3975 2650);
WIRE 16 -1 (-3075 2650)(-3525 2650);
WIRE 16 -1 (-3525 2650)(-3525 2775);
WIRE 16 -1 (-3975 2650)(-3975 2775);
WIRE 16 -1 (-3975 2650)(-4425 2650);
WIRE 16 -1 (-4425 2650)(-4425 2775);
WIRE 16 -1 (-2625 2650)(-3075 2650);
WIRE 16 -1 (-3075 2650)(-3075 2775);
WIRE 16 -1 (-2175 2650)(-2625 2650);
WIRE 16 -1 (-2625 2650)(-2625 2775);
WIRE 16 -1 (-1725 2650)(-2175 2650);
WIRE 16 -1 (-2175 2650)(-2175 2775);
WIRE 16 -1 (-1275 2650)(-1725 2650);
WIRE 16 -1 (-1725 2650)(-1725 2775);
WIRE 16 -1 (-825 2650)(-1275 2650);
WIRE 16 -1 (-1275 2650)(-1275 2775);
WIRE 16 -1 (-825 2650)(-425 2650);
WIRE 16 -1 (-825 2650)(-825 2775);
WIRE 16 -1 (-425 2650)(-425 2775);
WIRE 16 -1 (-425 2550)(-425 2650);
WIRE 16 -1 (-3075 2250)(-3525 2250);
WIRE 16 -1 (-2625 2250)(-3075 2250);
WIRE 16 -1 (-3075 2175)(-3075 2250);
WIRE 16 -1 (-3525 2250)(-3525 2175);
WIRE 16 -1 (-3525 2250)(-3975 2250);
WIRE 16 -1 (-3975 2175)(-3975 2250);
WIRE 16 -1 (-3975 2250)(-4425 2250);
WIRE 16 -1 (-2625 2175)(-2625 2250);
WIRE 16 -1 (-4425 2250)(-4425 2300);
WIRE 16 -1 (-4425 2250)(-4425 2175);
WIRE 16 -1 (-3525 1850)(-3975 1850);
WIRE 16 -1 (-3075 1850)(-3525 1850);
WIRE 16 -1 (-3525 1850)(-3525 1975);
WIRE 16 -1 (-3975 1850)(-3975 1975);
WIRE 16 -1 (-3975 1850)(-4425 1850);
WIRE 16 -1 (-4425 1850)(-4425 1975);
WIRE 16 -1 (-2625 1850)(-3075 1850);
WIRE 16 -1 (-3075 1850)(-3075 1975);
WIRE 16 -1 (-2625 1850)(-2625 1975);
WIRE 16 -1 (-2625 1775)(-2625 1850);
WIRE 16 3135 (-4600 6100)(-100 6100);
WIRE 16 3135 (-4600 800)(-4600 6100);
WIRE 16 3135 (-4600 800)(-100 800);
WIRE 16 3135 (-50 800)(-50 6100);
DOT 1 (-8550 2650);
DOT 1 (-6750 5025);
DOT 1 (-825 5425);
DOT 1 (-425 5025);
DOT 1 (-425 4250);
DOT 1 (-825 4650);
DOT 1 (-825 5025);
DOT 1 (-825 4250);
DOT 1 (-1275 5425);
DOT 1 (-1725 5425);
DOT 1 (-1275 5025);
DOT 1 (-1275 4650);
DOT 1 (-1275 4250);
DOT 1 (-1725 5025);
DOT 1 (-1725 4650);
DOT 1 (-1725 4250);
DOT 1 (-2175 5425);
DOT 1 (-2625 5425);
DOT 1 (-3075 5425);
DOT 1 (-2175 5025);
DOT 1 (-2175 4650);
DOT 1 (-2175 4250);
DOT 1 (-2625 5025);
DOT 1 (-2625 4650);
DOT 1 (-3075 5025);
DOT 1 (-3075 4650);
DOT 1 (-2625 4250);
DOT 1 (-3075 4250);
DOT 1 (-3525 5425);
DOT 1 (-3975 5425);
DOT 1 (-3525 5025);
DOT 1 (-3525 4650);
DOT 1 (-3525 4250);
DOT 1 (-3975 5025);
DOT 1 (-3975 4650);
DOT 1 (-3975 4250);
DOT 1 (-425 3450);
DOT 1 (-825 3850);
DOT 1 (-825 3450);
DOT 1 (-425 2650);
DOT 1 (-825 3050);
DOT 1 (-825 2650);
DOT 1 (-1275 3850);
DOT 1 (-1275 3450);
DOT 1 (-1725 3850);
DOT 1 (-1725 3450);
DOT 1 (-1275 3050);
DOT 1 (-1275 2650);
DOT 1 (-1725 3050);
DOT 1 (-1725 2650);
DOT 1 (-2175 3850);
DOT 1 (-2175 3450);
DOT 1 (-2625 3850);
DOT 1 (-3075 3850);
DOT 1 (-2625 3450);
DOT 1 (-3075 3450);
DOT 1 (-2175 3050);
DOT 1 (-2175 2650);
DOT 1 (-2625 3050);
DOT 1 (-2625 2650);
DOT 1 (-3075 3050);
DOT 1 (-3075 2650);
DOT 1 (-3075 2250);
DOT 1 (-3525 3850);
DOT 1 (-3525 3450);
DOT 1 (-3975 3850);
DOT 1 (-3975 3450);
DOT 1 (-3525 3050);
DOT 1 (-3525 2650);
DOT 1 (-3525 2250);
DOT 1 (-3975 3050);
DOT 1 (-3975 2650);
DOT 1 (-3975 2250);
DOT 1 (-2625 1850);
DOT 1 (-3075 1850);
DOT 1 (-3525 1850);
DOT 1 (-3975 1850);
DOT 1 (-4425 5425);
DOT 1 (-4425 4650);
DOT 1 (-5000 5025);
DOT 1 (-5000 4250);
DOT 1 (-5400 5425);
DOT 1 (-5850 5425);
DOT 1 (-5400 5025);
DOT 1 (-5400 4650);
DOT 1 (-5400 4250);
DOT 1 (-5850 5025);
DOT 1 (-5850 4650);
DOT 1 (-5850 4250);
DOT 1 (-6300 5425);
DOT 1 (-6750 5425);
DOT 1 (-7200 5425);
DOT 1 (-6300 5025);
DOT 1 (-6300 4650);
DOT 1 (-6300 4250);
DOT 1 (-6750 4650);
DOT 1 (-7200 5025);
DOT 1 (-7200 4650);
DOT 1 (-6750 4250);
DOT 1 (-7200 4250);
DOT 1 (-7650 5425);
DOT 1 (-8100 5425);
DOT 1 (-7650 5025);
DOT 1 (-7650 4650);
DOT 1 (-7650 4250);
DOT 1 (-8100 5025);
DOT 1 (-8100 4650);
DOT 1 (-8100 4250);
DOT 1 (-4425 3850);
DOT 1 (-5000 3450);
DOT 1 (-4425 3050);
DOT 1 (-4425 2250);
DOT 1 (-5000 2650);
DOT 1 (-5400 3850);
DOT 1 (-5400 3450);
DOT 1 (-5850 3850);
DOT 1 (-5850 3450);
DOT 1 (-5400 3050);
DOT 1 (-5400 2650);
DOT 1 (-5850 3050);
DOT 1 (-5850 2650);
DOT 1 (-6300 3850);
DOT 1 (-6750 3850);
DOT 1 (-7200 3850);
DOT 1 (-6750 3450);
DOT 1 (-7200 3450);
DOT 1 (-6300 3050);
DOT 1 (-6300 2650);
DOT 1 (-6750 3050);
DOT 1 (-6750 2650);
DOT 1 (-7200 3050);
DOT 1 (-7200 2650);
DOT 1 (-7650 3850);
DOT 1 (-7650 3450);
DOT 1 (-8100 3850);
DOT 1 (-8100 3450);
DOT 1 (-7650 3050);
DOT 1 (-7650 2650);
DOT 1 (-7650 2250);
DOT 1 (-8100 3050);
DOT 1 (-8100 2650);
DOT 1 (-8100 2250);
DOT 1 (-7200 1850);
DOT 1 (-7650 1850);
DOT 1 (-8100 1850);
DOT 1 (-8550 5425);
DOT 1 (-9000 5425);
DOT 1 (-8550 5025);
DOT 1 (-8550 4650);
DOT 1 (-8550 4250);
DOT 1 (-9000 4650);
DOT 1 (-8550 3850);
DOT 1 (-8550 3450);
DOT 1 (-9000 3850);
DOT 1 (-8550 3050);
DOT 1 (-8550 2250);
DOT 1 (-9000 3050);
DOT 1 (-9000 2250);
DOT 1 (-8550 1850);
DOT 1 (-9150 800);
DOT 1 (-9150 6100);
DOT 1 (-6300 3450);
FORCENOTE
10
(-5050 5525) 0;
DISPLAY LEFT (-5050 5525);
DISPLAY 1.021277 (-5050 5525);
PAINT SKYBLUE (-5050 5525);
FORCENOTE
10
(-475 5525) 0;
DISPLAY LEFT (-475 5525);
DISPLAY 1.021277 (-475 5525);
PAINT SKYBLUE (-475 5525);
FORCENOTE
5
(-2650 5550) 0;
DISPLAY LEFT (-2650 5550);
DISPLAY 1.021277 (-2650 5550);
PAINT SKYBLUE (-2650 5550);
FORCENOTE
5
(-2650 2350) 0;
DISPLAY LEFT (-2650 2350);
DISPLAY 1.021277 (-2650 2350);
PAINT SKYBLUE (-2650 2350);
FORCENOTE
5
(-7225 5525) 0;
DISPLAY LEFT (-7225 5525);
DISPLAY 1.021277 (-7225 5525);
PAINT SKYBLUE (-7225 5525);
FORCENOTE
PVDDCR_CPU0_P0: 45PCS 22UF ON BOT
(-9125 5825) 0;
DISPLAY LEFT (-9125 5825);
DISPLAY 2.510638 (-9125 5825);
PAINT WHITE (-9125 5825);
FORCENOTE
PVDDCR_CPU1_P0: 45PCS 22UF ON BOT
(-4475 5850) 0;
DISPLAY LEFT (-4475 5850);
DISPLAY 2.510638 (-4475 5850);
PAINT WHITE (-4475 5850);
QUIT
